(kicad_sch
	(version 20250114)
	(generator "eeschema")
	(generator_version "9.0")
	(paper "A3")
	(title_block
		(title "RDIMM DDR5 Tester")
		(date "2026-05-21")
		(rev "2.2.0")
		(company "Antmicro")
		(comment 1 "www.antmicro.com")
		(comment 2 "Antmicro")
	)
	(text "Power multiplexer\n"
		(exclude_from_sim no)
		(at 13.335 90.17 0)
		(effects
			(font
				(size 2 2)
				(thickness 0.508)
				(bold yes)
			)
			(justify left bottom)
		)
	)
	(text "HDMI OUT"
		(exclude_from_sim no)
		(at 13.335 144.145 0)
		(effects
			(font
				(size 3 3)
				(thickness 0.5994)
				(bold yes)
			)
			(justify left bottom)
		)
	)
	(text "TVS IN"
		(exclude_from_sim no)
		(at 274.32 184.15 0)
		(effects
			(font
				(size 2 2)
				(thickness 0.508)
				(bold yes)
			)
			(justify left bottom)
		)
	)
	(text "TVS OUT"
		(exclude_from_sim no)
		(at 274.32 224.155 0)
		(effects
			(font
				(size 2 2)
				(thickness 0.508)
				(bold yes)
			)
			(justify left bottom)
		)
	)
	(text "uSD card slot"
		(exclude_from_sim no)
		(at 129.54 17.78 0)
		(effects
			(font
				(size 2 2)
				(thickness 0.508)
				(bold yes)
			)
			(justify left bottom)
		)
	)
	(text "EEPROM"
		(exclude_from_sim no)
		(at 186.69 250.19 0)
		(effects
			(font
				(size 2 2)
				(thickness 0.508)
				(bold yes)
			)
			(justify left bottom)
		)
	)
	(text "VCCB:\n- 1V8 for SEL= H\n- 3V3 for SEL= L"
		(exclude_from_sim no)
		(at 63.5 133.985 0)
		(effects
			(font
				(size 1.27 1.27)
			)
			(justify left bottom)
		)
	)
	(text "Bootstrap configuration"
		(exclude_from_sim no)
		(at 13.335 250.19 0)
		(effects
			(font
				(size 2 2)
				(thickness 0.5994)
				(bold yes)
			)
			(justify left bottom)
		)
	)
	(text "HDMI IN"
		(exclude_from_sim no)
		(at 273.685 19.685 0)
		(effects
			(font
				(size 3 3)
				(thickness 0.5994)
				(bold yes)
			)
			(justify left bottom)
		)
	)
	(text "SD 3.0 card "
		(exclude_from_sim no)
		(at 14.605 19.685 0)
		(effects
			(font
				(size 3 3)
				(thickness 0.5994)
				(bold yes)
			)
			(justify left bottom)
		)
	)
	(text "HDMI retimer"
		(exclude_from_sim no)
		(at 13.335 149.225 0)
		(effects
			(font
				(size 2 2)
				(thickness 0.5994)
				(bold yes)
			)
			(justify left bottom)
		)
	)
	(text "Logic level translator"
		(exclude_from_sim no)
		(at 273.685 143.51 0)
		(effects
			(font
				(size 2 2)
				(thickness 0.508)
				(bold yes)
			)
			(justify left bottom)
		)
	)
	(text "Voltage level translator"
		(exclude_from_sim no)
		(at 14.605 24.765 0)
		(effects
			(font
				(size 2 2)
				(thickness 0.5994)
				(bold yes)
			)
			(justify left bottom)
		)
	)
	(text "HDMI input connector"
		(exclude_from_sim no)
		(at 273.685 23.495 0)
		(effects
			(font
				(size 2 2)
				(thickness 0.5994)
				(bold yes)
			)
			(justify left bottom)
		)
	)
	(text "HDMI output connector"
		(exclude_from_sim no)
		(at 160.655 144.145 0)
		(effects
			(font
				(size 2 2)
				(thickness 0.5994)
				(bold yes)
			)
			(justify left bottom)
		)
	)
	(text "Decoupling"
		(exclude_from_sim no)
		(at 93.98 250.19 0)
		(effects
			(font
				(size 2 2)
				(thickness 0.5994)
				(bold yes)
			)
			(justify left bottom)
		)
	)
	(junction
		(at 245.11 205.74)
		(diameter 0)
		(color 0 0 0 0)
	)
	(junction
		(at 46.99 163.83)
		(diameter 0)
		(color 0 0 0 0)
	)
	(junction
		(at 389.89 91.44)
		(diameter 0)
		(color 0 0 0 0)
	)
	(junction
		(at 163.83 85.09)
		(diameter 0)
		(color 0 0 0 0)
	)
	(junction
		(at 153.67 274.32)
		(diameter 0)
		(color 0 0 0 0)
	)
	(junction
		(at 370.84 31.75)
		(diameter 0)
		(color 0 0 0 0)
	)
	(junction
		(at 168.91 260.35)
		(diameter 0)
		(color 0 0 0 0)
	)
	(junction
		(at 109.22 260.35)
		(diameter 0)
		(color 0 0 0 0)
	)
	(junction
		(at 242.57 264.16)
		(diameter 0)
		(color 0 0 0 0)
	)
	(junction
		(at 353.06 66.04)
		(diameter 0)
		(color 0 0 0 0)
	)
	(junction
		(at 158.75 274.32)
		(diameter 0)
		(color 0 0 0 0)
	)
	(junction
		(at 328.93 78.74)
		(diameter 0)
		(color 0 0 0 0)
	)
	(junction
		(at 27.94 269.24)
		(diameter 0)
		(color 0 0 0 0)
	)
	(junction
		(at 46.99 193.04)
		(diameter 0)
		(color 0 0 0 0)
	)
	(junction
		(at 354.33 116.84)
		(diameter 0)
		(color 0 0 0 0)
	)
	(junction
		(at 158.75 260.35)
		(diameter 0)
		(color 0 0 0 0)
	)
	(junction
		(at 389.89 60.96)
		(diameter 0)
		(color 0 0 0 0)
	)
	(junction
		(at 27.94 274.32)
		(diameter 0)
		(color 0 0 0 0)
	)
	(junction
		(at 389.89 76.2)
		(diameter 0)
		(color 0 0 0 0)
	)
	(junction
		(at 365.76 125.73)
		(diameter 0)
		(color 0 0 0 0)
	)
	(junction
		(at 78.74 264.16)
		(diameter 0)
		(color 0 0 0 0)
	)
	(junction
		(at 361.95 31.75)
		(diameter 0)
		(color 0 0 0 0)
	)
	(junction
		(at 114.3 274.32)
		(diameter 0)
		(color 0 0 0 0)
	)
	(junction
		(at 345.44 71.12)
		(diameter 0)
		(color 0 0 0 0)
	)
	(junction
		(at 78.74 271.78)
		(diameter 0)
		(color 0 0 0 0)
	)
	(junction
		(at 389.89 68.58)
		(diameter 0)
		(color 0 0 0 0)
	)
	(junction
		(at 44.45 189.23)
		(diameter 0)
		(color 0 0 0 0)
	)
	(junction
		(at 336.55 31.75)
		(diameter 0)
		(color 0 0 0 0)
	)
	(junction
		(at 336.55 73.66)
		(diameter 0)
		(color 0 0 0 0)
	)
	(junction
		(at 339.09 162.56)
		(diameter 0)
		(color 0 0 0 0)
	)
	(junction
		(at 168.91 274.32)
		(diameter 0)
		(color 0 0 0 0)
	)
	(junction
		(at 311.15 31.75)
		(diameter 0)
		(color 0 0 0 0)
	)
	(junction
		(at 41.91 186.69)
		(diameter 0)
		(color 0 0 0 0)
	)
	(junction
		(at 137.16 260.35)
		(diameter 0)
		(color 0 0 0 0)
	)
	(junction
		(at 27.94 271.78)
		(diameter 0)
		(color 0 0 0 0)
	)
	(junction
		(at 78.74 274.32)
		(diameter 0)
		(color 0 0 0 0)
	)
	(junction
		(at 57.15 224.79)
		(diameter 0)
		(color 0 0 0 0)
	)
	(junction
		(at 173.99 260.35)
		(diameter 0)
		(color 0 0 0 0)
	)
	(junction
		(at 27.94 261.62)
		(diameter 0)
		(color 0 0 0 0)
	)
	(junction
		(at 261.62 220.98)
		(diameter 0)
		(color 0 0 0 0)
	)
	(junction
		(at 194.31 215.9)
		(diameter 0)
		(color 0 0 0 0)
	)
	(junction
		(at 49.53 195.58)
		(diameter 0)
		(color 0 0 0 0)
	)
	(junction
		(at 153.67 260.35)
		(diameter 0)
		(color 0 0 0 0)
	)
	(junction
		(at 182.88 215.9)
		(diameter 0)
		(color 0 0 0 0)
	)
	(junction
		(at 163.83 260.35)
		(diameter 0)
		(color 0 0 0 0)
	)
	(junction
		(at 27.94 266.7)
		(diameter 0)
		(color 0 0 0 0)
	)
	(junction
		(at 245.11 208.28)
		(diameter 0)
		(color 0 0 0 0)
	)
	(junction
		(at 78.74 269.24)
		(diameter 0)
		(color 0 0 0 0)
	)
	(junction
		(at 148.59 260.35)
		(diameter 0)
		(color 0 0 0 0)
	)
	(junction
		(at 41.91 163.83)
		(diameter 0)
		(color 0 0 0 0)
	)
	(junction
		(at 345.44 31.75)
		(diameter 0)
		(color 0 0 0 0)
	)
	(junction
		(at 78.74 266.7)
		(diameter 0)
		(color 0 0 0 0)
	)
	(junction
		(at 311.15 93.98)
		(diameter 0)
		(color 0 0 0 0)
	)
	(junction
		(at 119.38 274.32)
		(diameter 0)
		(color 0 0 0 0)
	)
	(junction
		(at 54.61 115.57)
		(diameter 0)
		(color 0 0 0 0)
	)
	(junction
		(at 144.78 179.07)
		(diameter 0)
		(color 0 0 0 0)
	)
	(junction
		(at 173.99 274.32)
		(diameter 0)
		(color 0 0 0 0)
	)
	(junction
		(at 114.3 260.35)
		(diameter 0)
		(color 0 0 0 0)
	)
	(junction
		(at 328.93 31.75)
		(diameter 0)
		(color 0 0 0 0)
	)
	(junction
		(at 245.11 213.36)
		(diameter 0)
		(color 0 0 0 0)
	)
	(junction
		(at 353.06 31.75)
		(diameter 0)
		(color 0 0 0 0)
	)
	(junction
		(at 78.74 276.86)
		(diameter 0)
		(color 0 0 0 0)
	)
	(junction
		(at 238.76 275.59)
		(diameter 0)
		(color 0 0 0 0)
	)
	(junction
		(at 370.84 58.42)
		(diameter 0)
		(color 0 0 0 0)
	)
	(junction
		(at 386.08 50.8)
		(diameter 0)
		(color 0 0 0 0)
	)
	(junction
		(at 378.46 55.88)
		(diameter 0)
		(color 0 0 0 0)
	)
	(junction
		(at 201.93 215.9)
		(diameter 0)
		(color 0 0 0 0)
	)
	(junction
		(at 389.89 53.34)
		(diameter 0)
		(color 0 0 0 0)
	)
	(junction
		(at 378.46 31.75)
		(diameter 0)
		(color 0 0 0 0)
	)
	(junction
		(at 300.99 104.14)
		(diameter 0)
		(color 0 0 0 0)
	)
	(junction
		(at 365.76 93.98)
		(diameter 0)
		(color 0 0 0 0)
	)
	(junction
		(at 245.11 210.82)
		(diameter 0)
		(color 0 0 0 0)
	)
	(junction
		(at 320.04 31.75)
		(diameter 0)
		(color 0 0 0 0)
	)
	(junction
		(at 250.19 220.98)
		(diameter 0)
		(color 0 0 0 0)
	)
	(junction
		(at 163.83 274.32)
		(diameter 0)
		(color 0 0 0 0)
	)
	(junction
		(at 44.45 163.83)
		(diameter 0)
		(color 0 0 0 0)
	)
	(junction
		(at 220.98 273.05)
		(diameter 0)
		(color 0 0 0 0)
	)
	(junction
		(at 341.63 93.98)
		(diameter 0)
		(color 0 0 0 0)
	)
	(junction
		(at 220.98 275.59)
		(diameter 0)
		(color 0 0 0 0)
	)
	(junction
		(at 261.62 229.87)
		(diameter 0)
		(color 0 0 0 0)
	)
	(junction
		(at 361.95 63.5)
		(diameter 0)
		(color 0 0 0 0)
	)
	(junction
		(at 27.94 264.16)
		(diameter 0)
		(color 0 0 0 0)
	)
	(no_connect
		(at 218.44 210.82)
	)
	(no_connect
		(at 109.22 193.04)
	)
	(no_connect
		(at 391.16 99.06)
	)
	(no_connect
		(at 218.44 203.2)
	)
	(no_connect
		(at 81.28 201.93)
	)
	(no_connect
		(at 81.28 199.39)
	)
	(no_connect
		(at 391.16 83.82)
	)
	(no_connect
		(at 391.16 81.28)
	)
	(no_connect
		(at 64.77 66.04)
	)
	(bus_entry
		(at 306.07 50.8)
		(size -2.54 -2.54)
		(stroke
			(width 0)
			(type default)
		)
	)
	(bus_entry
		(at 38.1 195.58)
		(size -2.54 -2.54)
		(stroke
			(width 0)
			(type default)
		)
	)
	(bus_entry
		(at 322.58 165.1)
		(size -2.54 -2.54)
		(stroke
			(width 0)
			(type default)
		)
	)
	(bus_entry
		(at 48.26 48.26)
		(size -2.54 -2.54)
		(stroke
			(width 0)
			(type default)
		)
	)
	(bus_entry
		(at 48.26 55.88)
		(size -2.54 -2.54)
		(stroke
			(width 0)
			(type default)
		)
	)
	(bus_entry
		(at 60.96 175.26)
		(size -2.54 -2.54)
		(stroke
			(width 0)
			(type default)
		)
	)
	(bus_entry
		(at 60.96 177.8)
		(size -2.54 -2.54)
		(stroke
			(width 0)
			(type default)
		)
	)
	(bus_entry
		(at 306.07 58.42)
		(size -2.54 -2.54)
		(stroke
			(width 0)
			(type default)
		)
	)
	(bus_entry
		(at 60.96 180.34)
		(size -2.54 -2.54)
		(stroke
			(width 0)
			(type default)
		)
	)
	(bus_entry
		(at 48.26 45.72)
		(size -2.54 -2.54)
		(stroke
			(width 0)
			(type default)
		)
	)
	(bus_entry
		(at 306.07 66.04)
		(size -2.54 -2.54)
		(stroke
			(width 0)
			(type default)
		)
	)
	(bus_entry
		(at 306.07 71.12)
		(size -2.54 -2.54)
		(stroke
			(width 0)
			(type default)
		)
	)
	(bus_entry
		(at 48.26 53.34)
		(size -2.54 -2.54)
		(stroke
			(width 0)
			(type default)
		)
	)
	(bus_entry
		(at 60.96 165.1)
		(size -2.54 -2.54)
		(stroke
			(width 0)
			(type default)
		)
	)
	(bus_entry
		(at 60.96 172.72)
		(size -2.54 -2.54)
		(stroke
			(width 0)
			(type default)
		)
	)
	(bus_entry
		(at 306.07 73.66)
		(size -2.54 -2.54)
		(stroke
			(width 0)
			(type default)
		)
	)
	(bus_entry
		(at 60.96 162.56)
		(size -2.54 -2.54)
		(stroke
			(width 0)
			(type default)
		)
	)
	(bus_entry
		(at 306.07 63.5)
		(size -2.54 -2.54)
		(stroke
			(width 0)
			(type default)
		)
	)
	(bus_entry
		(at 60.96 170.18)
		(size -2.54 -2.54)
		(stroke
			(width 0)
			(type default)
		)
	)
	(bus_entry
		(at 45.72 76.2)
		(size 2.54 2.54)
		(stroke
			(width 0)
			(type default)
		)
	)
	(bus_entry
		(at 38.1 186.69)
		(size -2.54 -2.54)
		(stroke
			(width 0)
			(type default)
		)
	)
	(bus_entry
		(at 306.07 55.88)
		(size -2.54 -2.54)
		(stroke
			(width 0)
			(type default)
		)
	)
	(bus_entry
		(at 38.1 193.04)
		(size -2.54 -2.54)
		(stroke
			(width 0)
			(type default)
		)
	)
	(bus_entry
		(at 60.96 167.64)
		(size -2.54 -2.54)
		(stroke
			(width 0)
			(type default)
		)
	)
	(bus_entry
		(at 322.58 167.64)
		(size -2.54 -2.54)
		(stroke
			(width 0)
			(type default)
		)
	)
	(bus_entry
		(at 48.26 58.42)
		(size -2.54 -2.54)
		(stroke
			(width 0)
			(type default)
		)
	)
	(bus_entry
		(at 306.07 78.74)
		(size -2.54 -2.54)
		(stroke
			(width 0)
			(type default)
		)
	)
	(bus_entry
		(at 38.1 189.23)
		(size -2.54 -2.54)
		(stroke
			(width 0)
			(type default)
		)
	)
	(bus_entry
		(at 48.26 60.96)
		(size -2.54 -2.54)
		(stroke
			(width 0)
			(type default)
		)
	)
	(wire
		(pts
			(xy 114.3 274.32) (xy 114.3 269.24)
		)
		(stroke
			(width 0)
			(type default)
		)
	)
	(wire
		(pts
			(xy 370.84 233.68) (xy 387.35 233.68)
		)
		(stroke
			(width 0)
			(type default)
		)
	)
	(wire
		(pts
			(xy 201.93 215.9) (xy 201.93 219.71)
		)
		(stroke
			(width 0)
			(type default)
		)
	)
	(wire
		(pts
			(xy 340.36 204.47) (xy 340.36 208.28)
		)
		(stroke
			(width 0)
			(type default)
		)
	)
	(wire
		(pts
			(xy 60.96 165.1) (xy 81.28 165.1)
		)
		(stroke
			(width 0)
			(type default)
		)
	)
	(wire
		(pts
			(xy 307.34 243.84) (xy 307.34 245.11)
		)
		(stroke
			(width 0)
			(type default)
		)
	)
	(wire
		(pts
			(xy 336.55 73.66) (xy 391.16 73.66)
		)
		(stroke
			(width 0)
			(type default)
		)
	)
	(wire
		(pts
			(xy 48.26 48.26) (xy 64.77 48.26)
		)
		(stroke
			(width 0)
			(type default)
		)
	)
	(polyline
		(pts
			(xy 128.27 12.7) (xy 128.27 138.43)
		)
		(stroke
			(width 0)
			(type default)
		)
	)
	(wire
		(pts
			(xy 190.5 64.77) (xy 191.77 64.77)
		)
		(stroke
			(width 0)
			(type default)
		)
	)
	(bus
		(pts
			(xy 58.42 172.72) (xy 58.42 175.26)
		)
		(stroke
			(width 0)
			(type default)
		)
	)
	(wire
		(pts
			(xy 222.25 270.51) (xy 220.98 270.51)
		)
		(stroke
			(width 0)
			(type default)
		)
	)
	(wire
		(pts
			(xy 80.01 156.21) (xy 81.28 156.21)
		)
		(stroke
			(width 0)
			(type default)
		)
	)
	(bus
		(pts
			(xy 303.53 71.12) (xy 303.53 76.2)
		)
		(stroke
			(width 0)
			(type default)
		)
	)
	(wire
		(pts
			(xy 328.93 31.75) (xy 336.55 31.75)
		)
		(stroke
			(width 0)
			(type default)
		)
	)
	(wire
		(pts
			(xy 78.74 276.86) (xy 78.74 278.13)
		)
		(stroke
			(width 0)
			(type default)
		)
	)
	(wire
		(pts
			(xy 46.99 175.26) (xy 46.99 163.83)
		)
		(stroke
			(width 0)
			(type default)
		)
	)
	(bus
		(pts
			(xy 45.72 50.8) (xy 45.72 53.34)
		)
		(stroke
			(width 0)
			(type default)
		)
	)
	(wire
		(pts
			(xy 306.07 203.2) (xy 306.07 207.01)
		)
		(stroke
			(width 0)
			(type default)
		)
	)
	(wire
		(pts
			(xy 306.07 50.8) (xy 386.08 50.8)
		)
		(stroke
			(width 0)
			(type default)
		)
	)
	(wire
		(pts
			(xy 325.12 201.93) (xy 341.63 201.93)
		)
		(stroke
			(width 0)
			(type default)
		)
	)
	(wire
		(pts
			(xy 109.22 184.15) (xy 113.03 184.15)
		)
		(stroke
			(width 0)
			(type default)
		)
	)
	(wire
		(pts
			(xy 339.09 157.48) (xy 339.09 162.56)
		)
		(stroke
			(width 0)
			(type default)
		)
	)
	(wire
		(pts
			(xy 195.58 165.1) (xy 218.44 165.1)
		)
		(stroke
			(width 0)
			(type default)
		)
	)
	(wire
		(pts
			(xy 67.31 227.33) (xy 67.31 228.6)
		)
		(stroke
			(width 0)
			(type default)
		)
	)
	(wire
		(pts
			(xy 190.5 63.5) (xy 190.5 64.77)
		)
		(stroke
			(width 0)
			(type default)
		)
	)
	(wire
		(pts
			(xy 148.59 274.32) (xy 153.67 274.32)
		)
		(stroke
			(width 0)
			(type default)
		)
	)
	(wire
		(pts
			(xy 71.12 264.16) (xy 78.74 264.16)
		)
		(stroke
			(width 0)
			(type default)
		)
	)
	(wire
		(pts
			(xy 133.35 180.34) (xy 109.22 180.34)
		)
		(stroke
			(width 0)
			(type default)
		)
	)
	(wire
		(pts
			(xy 109.22 259.08) (xy 109.22 260.35)
		)
		(stroke
			(width 0)
			(type default)
		)
	)
	(wire
		(pts
			(xy 365.76 92.71) (xy 365.76 93.98)
		)
		(stroke
			(width 0)
			(type default)
		)
	)
	(wire
		(pts
			(xy 353.06 31.75) (xy 353.06 33.02)
		)
		(stroke
			(width 0)
			(type default)
		)
	)
	(wire
		(pts
			(xy 222.25 275.59) (xy 220.98 275.59)
		)
		(stroke
			(width 0)
			(type default)
		)
	)
	(wire
		(pts
			(xy 148.59 69.85) (xy 191.77 69.85)
		)
		(stroke
			(width 0)
			(type default)
		)
	)
	(wire
		(pts
			(xy 54.61 120.65) (xy 69.85 120.65)
		)
		(stroke
			(width 0)
			(type default)
		)
	)
	(wire
		(pts
			(xy 290.83 198.12) (xy 307.34 198.12)
		)
		(stroke
			(width 0)
			(type default)
		)
	)
	(wire
		(pts
			(xy 243.84 208.28) (xy 245.11 208.28)
		)
		(stroke
			(width 0)
			(type default)
		)
	)
	(wire
		(pts
			(xy 44.45 189.23) (xy 81.28 189.23)
		)
		(stroke
			(width 0)
			(type default)
		)
	)
	(wire
		(pts
			(xy 243.84 210.82) (xy 245.11 210.82)
		)
		(stroke
			(width 0)
			(type default)
		)
	)
	(wire
		(pts
			(xy 391.16 53.34) (xy 389.89 53.34)
		)
		(stroke
			(width 0)
			(type default)
		)
	)
	(wire
		(pts
			(xy 341.63 194.31) (xy 325.12 194.31)
		)
		(stroke
			(width 0)
			(type default)
		)
	)
	(wire
		(pts
			(xy 119.38 275.59) (xy 119.38 274.32)
		)
		(stroke
			(width 0)
			(type default)
		)
	)
	(wire
		(pts
			(xy 53.34 113.03) (xy 69.85 113.03)
		)
		(stroke
			(width 0)
			(type default)
		)
	)
	(wire
		(pts
			(xy 168.91 274.32) (xy 168.91 269.24)
		)
		(stroke
			(width 0)
			(type default)
		)
	)
	(wire
		(pts
			(xy 60.96 172.72) (xy 81.28 172.72)
		)
		(stroke
			(width 0)
			(type default)
		)
	)
	(wire
		(pts
			(xy 163.83 85.09) (xy 163.83 90.17)
		)
		(stroke
			(width 0)
			(type default)
		)
	)
	(bus
		(pts
			(xy 318.77 160.02) (xy 320.04 161.29)
		)
		(stroke
			(width 0)
			(type default)
		)
	)
	(wire
		(pts
			(xy 290.83 193.04) (xy 307.34 193.04)
		)
		(stroke
			(width 0)
			(type default)
		)
	)
	(wire
		(pts
			(xy 336.55 38.1) (xy 336.55 40.64)
		)
		(stroke
			(width 0)
			(type default)
		)
	)
	(wire
		(pts
			(xy 55.88 71.12) (xy 55.88 72.39)
		)
		(stroke
			(width 0)
			(type default)
		)
	)
	(wire
		(pts
			(xy 370.84 241.3) (xy 387.35 241.3)
		)
		(stroke
			(width 0)
			(type default)
		)
	)
	(wire
		(pts
			(xy 176.53 259.08) (xy 176.53 260.35)
		)
		(stroke
			(width 0)
			(type default)
		)
	)
	(wire
		(pts
			(xy 237.49 269.24) (xy 238.76 269.24)
		)
		(stroke
			(width 0)
			(type default)
		)
	)
	(wire
		(pts
			(xy 114.3 260.35) (xy 109.22 260.35)
		)
		(stroke
			(width 0)
			(type default)
		)
	)
	(wire
		(pts
			(xy 21.59 107.95) (xy 21.59 109.22)
		)
		(stroke
			(width 0)
			(type default)
		)
	)
	(wire
		(pts
			(xy 307.34 203.2) (xy 306.07 203.2)
		)
		(stroke
			(width 0)
			(type default)
		)
	)
	(wire
		(pts
			(xy 358.14 195.58) (xy 379.73 195.58)
		)
		(stroke
			(width 0)
			(type default)
		)
	)
	(bus
		(pts
			(xy 58.42 158.75) (xy 58.42 160.02)
		)
		(stroke
			(width 0)
			(type default)
		)
	)
	(wire
		(pts
			(xy 320.04 31.75) (xy 328.93 31.75)
		)
		(stroke
			(width 0)
			(type default)
		)
	)
	(bus
		(pts
			(xy 302.26 44.45) (xy 303.53 45.72)
		)
		(stroke
			(width 0)
			(type default)
		)
	)
	(wire
		(pts
			(xy 109.22 264.16) (xy 109.22 260.35)
		)
		(stroke
			(width 0)
			(type default)
		)
	)
	(wire
		(pts
			(xy 46.99 193.04) (xy 81.28 193.04)
		)
		(stroke
			(width 0)
			(type default)
		)
	)
	(polyline
		(pts
			(xy 273.05 179.07) (xy 407.67 179.07)
		)
		(stroke
			(width 0)
			(type default)
		)
	)
	(wire
		(pts
			(xy 358.14 198.12) (xy 379.73 198.12)
		)
		(stroke
			(width 0)
			(type default)
		)
	)
	(wire
		(pts
			(xy 345.44 31.75) (xy 353.06 31.75)
		)
		(stroke
			(width 0)
			(type default)
		)
	)
	(wire
		(pts
			(xy 245.11 205.74) (xy 245.11 208.28)
		)
		(stroke
			(width 0)
			(type default)
		)
	)
	(polyline
		(pts
			(xy 12.7 85.09) (xy 127 85.09)
		)
		(stroke
			(width 0)
			(type default)
		)
	)
	(wire
		(pts
			(xy 81.28 208.28) (xy 66.04 208.28)
		)
		(stroke
			(width 0)
			(type default)
		)
	)
	(wire
		(pts
			(xy 44.45 175.26) (xy 44.45 163.83)
		)
		(stroke
			(width 0)
			(type default)
		)
	)
	(wire
		(pts
			(xy 60.96 180.34) (xy 81.28 180.34)
		)
		(stroke
			(width 0)
			(type default)
		)
	)
	(bus
		(pts
			(xy 303.53 53.34) (xy 303.53 55.88)
		)
		(stroke
			(width 0)
			(type default)
		)
	)
	(wire
		(pts
			(xy 200.66 195.58) (xy 218.44 195.58)
		)
		(stroke
			(width 0)
			(type default)
		)
	)
	(bus
		(pts
			(xy 45.72 43.18) (xy 45.72 45.72)
		)
		(stroke
			(width 0)
			(type default)
		)
	)
	(wire
		(pts
			(xy 358.14 170.18) (xy 359.41 170.18)
		)
		(stroke
			(width 0)
			(type default)
		)
	)
	(wire
		(pts
			(xy 378.46 38.1) (xy 378.46 40.64)
		)
		(stroke
			(width 0)
			(type default)
		)
	)
	(wire
		(pts
			(xy 27.94 271.78) (xy 27.94 274.32)
		)
		(stroke
			(width 0)
			(type default)
		)
	)
	(wire
		(pts
			(xy 389.89 68.58) (xy 389.89 76.2)
		)
		(stroke
			(width 0)
			(type default)
		)
	)
	(wire
		(pts
			(xy 177.8 59.69) (xy 177.8 60.96)
		)
		(stroke
			(width 0)
			(type default)
		)
	)
	(wire
		(pts
			(xy 144.78 179.07) (xy 144.78 180.34)
		)
		(stroke
			(width 0)
			(type default)
		)
	)
	(polyline
		(pts
			(xy 92.71 245.11) (xy 92.71 285.75)
		)
		(stroke
			(width 0)
			(type default)
		)
	)
	(wire
		(pts
			(xy 148.59 74.93) (xy 191.77 74.93)
		)
		(stroke
			(width 0)
			(type default)
		)
	)
	(wire
		(pts
			(xy 297.18 104.14) (xy 300.99 104.14)
		)
		(stroke
			(width 0)
			(type default)
		)
	)
	(bus
		(pts
			(xy 58.42 170.18) (xy 58.42 172.72)
		)
		(stroke
			(width 0)
			(type default)
		)
	)
	(wire
		(pts
			(xy 365.76 93.98) (xy 391.16 93.98)
		)
		(stroke
			(width 0)
			(type default)
		)
	)
	(bus
		(pts
			(xy 33.02 187.96) (xy 34.29 187.96)
		)
		(stroke
			(width 0)
			(type default)
		)
	)
	(bus
		(pts
			(xy 45.72 45.72) (xy 45.72 50.8)
		)
		(stroke
			(width 0)
			(type default)
		)
	)
	(wire
		(pts
			(xy 336.55 31.75) (xy 336.55 33.02)
		)
		(stroke
			(width 0)
			(type default)
		)
	)
	(wire
		(pts
			(xy 148.59 77.47) (xy 191.77 77.47)
		)
		(stroke
			(width 0)
			(type default)
		)
	)
	(wire
		(pts
			(xy 370.84 38.1) (xy 370.84 40.64)
		)
		(stroke
			(width 0)
			(type default)
		)
	)
	(wire
		(pts
			(xy 80.01 231.14) (xy 81.28 231.14)
		)
		(stroke
			(width 0)
			(type default)
		)
	)
	(wire
		(pts
			(xy 389.89 53.34) (xy 389.89 60.96)
		)
		(stroke
			(width 0)
			(type default)
		)
	)
	(wire
		(pts
			(xy 387.35 158.75) (xy 387.35 161.29)
		)
		(stroke
			(width 0)
			(type default)
		)
	)
	(wire
		(pts
			(xy 67.31 233.68) (xy 67.31 234.95)
		)
		(stroke
			(width 0)
			(type default)
		)
	)
	(wire
		(pts
			(xy 153.67 274.32) (xy 153.67 269.24)
		)
		(stroke
			(width 0)
			(type default)
		)
	)
	(wire
		(pts
			(xy 49.53 180.34) (xy 49.53 195.58)
		)
		(stroke
			(width 0)
			(type default)
		)
	)
	(wire
		(pts
			(xy 311.15 31.75) (xy 311.15 34.29)
		)
		(stroke
			(width 0)
			(type default)
		)
	)
	(wire
		(pts
			(xy 311.15 93.98) (xy 325.12 93.98)
		)
		(stroke
			(width 0)
			(type default)
		)
	)
	(wire
		(pts
			(xy 326.39 242.57) (xy 350.52 242.57)
		)
		(stroke
			(width 0)
			(type default)
		)
	)
	(wire
		(pts
			(xy 19.05 44.45) (xy 19.05 45.72)
		)
		(stroke
			(width 0)
			(type default)
		)
	)
	(wire
		(pts
			(xy 242.57 262.89) (xy 242.57 264.16)
		)
		(stroke
			(width 0)
			(type default)
		)
	)
	(wire
		(pts
			(xy 350.52 245.11) (xy 349.25 245.11)
		)
		(stroke
			(width 0)
			(type default)
		)
	)
	(wire
		(pts
			(xy 81.28 218.44) (xy 66.04 218.44)
		)
		(stroke
			(width 0)
			(type default)
		)
	)
	(wire
		(pts
			(xy 378.46 55.88) (xy 391.16 55.88)
		)
		(stroke
			(width 0)
			(type default)
		)
	)
	(polyline
		(pts
			(xy 271.78 245.11) (xy 185.42 245.11)
		)
		(stroke
			(width 0)
			(type default)
		)
	)
	(wire
		(pts
			(xy 340.36 170.18) (xy 339.09 170.18)
		)
		(stroke
			(width 0)
			(type default)
		)
	)
	(wire
		(pts
			(xy 389.89 48.26) (xy 391.16 48.26)
		)
		(stroke
			(width 0)
			(type default)
		)
	)
	(wire
		(pts
			(xy 27.94 264.16) (xy 27.94 266.7)
		)
		(stroke
			(width 0)
			(type default)
		)
	)
	(wire
		(pts
			(xy 378.46 31.75) (xy 378.46 33.02)
		)
		(stroke
			(width 0)
			(type default)
		)
	)
	(wire
		(pts
			(xy 157.48 176.53) (xy 144.78 176.53)
		)
		(stroke
			(width 0)
			(type default)
		)
	)
	(wire
		(pts
			(xy 57.15 224.79) (xy 57.15 228.6)
		)
		(stroke
			(width 0)
			(type default)
		)
	)
	(wire
		(pts
			(xy 370.84 31.75) (xy 370.84 33.02)
		)
		(stroke
			(width 0)
			(type default)
		)
	)
	(wire
		(pts
			(xy 90.17 113.03) (xy 87.63 113.03)
		)
		(stroke
			(width 0)
			(type default)
		)
	)
	(wire
		(pts
			(xy 328.93 78.74) (xy 391.16 78.74)
		)
		(stroke
			(width 0)
			(type default)
		)
	)
	(wire
		(pts
			(xy 345.44 71.12) (xy 391.16 71.12)
		)
		(stroke
			(width 0)
			(type default)
		)
	)
	(wire
		(pts
			(xy 39.37 271.78) (xy 66.04 271.78)
		)
		(stroke
			(width 0)
			(type default)
		)
	)
	(wire
		(pts
			(xy 243.84 203.2) (xy 245.11 203.2)
		)
		(stroke
			(width 0)
			(type default)
		)
	)
	(wire
		(pts
			(xy 194.31 214.63) (xy 194.31 215.9)
		)
		(stroke
			(width 0)
			(type default)
		)
	)
	(wire
		(pts
			(xy 60.96 177.8) (xy 81.28 177.8)
		)
		(stroke
			(width 0)
			(type default)
		)
	)
	(wire
		(pts
			(xy 148.59 264.16) (xy 148.59 260.35)
		)
		(stroke
			(width 0)
			(type default)
		)
	)
	(bus
		(pts
			(xy 303.53 48.26) (xy 303.53 53.34)
		)
		(stroke
			(width 0)
			(type default)
		)
	)
	(wire
		(pts
			(xy 158.75 274.32) (xy 158.75 269.24)
		)
		(stroke
			(width 0)
			(type default)
		)
	)
	(wire
		(pts
			(xy 359.41 170.18) (xy 359.41 171.45)
		)
		(stroke
			(width 0)
			(type default)
		)
	)
	(wire
		(pts
			(xy 195.58 172.72) (xy 218.44 172.72)
		)
		(stroke
			(width 0)
			(type default)
		)
	)
	(bus
		(pts
			(xy 58.42 167.64) (xy 58.42 170.18)
		)
		(stroke
			(width 0)
			(type default)
		)
	)
	(bus
		(pts
			(xy 303.53 55.88) (xy 303.53 60.96)
		)
		(stroke
			(width 0)
			(type default)
		)
	)
	(wire
		(pts
			(xy 80.01 182.88) (xy 80.01 184.15)
		)
		(stroke
			(width 0)
			(type default)
		)
	)
	(wire
		(pts
			(xy 237.49 264.16) (xy 242.57 264.16)
		)
		(stroke
			(width 0)
			(type default)
		)
	)
	(wire
		(pts
			(xy 386.08 243.84) (xy 387.35 243.84)
		)
		(stroke
			(width 0)
			(type default)
		)
	)
	(wire
		(pts
			(xy 345.44 38.1) (xy 345.44 40.64)
		)
		(stroke
			(width 0)
			(type default)
		)
	)
	(wire
		(pts
			(xy 153.67 264.16) (xy 153.67 260.35)
		)
		(stroke
			(width 0)
			(type default)
		)
	)
	(wire
		(pts
			(xy 102.87 106.68) (xy 102.87 109.22)
		)
		(stroke
			(width 0)
			(type default)
		)
	)
	(bus
		(pts
			(xy 45.72 58.42) (xy 45.72 76.2)
		)
		(stroke
			(width 0)
			(type default)
		)
	)
	(wire
		(pts
			(xy 386.08 31.75) (xy 386.08 33.02)
		)
		(stroke
			(width 0)
			(type default)
		)
	)
	(wire
		(pts
			(xy 379.73 205.74) (xy 378.46 205.74)
		)
		(stroke
			(width 0)
			(type default)
		)
	)
	(wire
		(pts
			(xy 378.46 205.74) (xy 378.46 209.55)
		)
		(stroke
			(width 0)
			(type default)
		)
	)
	(wire
		(pts
			(xy 49.53 195.58) (xy 81.28 195.58)
		)
		(stroke
			(width 0)
			(type default)
		)
	)
	(wire
		(pts
			(xy 83.82 53.34) (xy 100.33 53.34)
		)
		(stroke
			(width 0)
			(type default)
		)
	)
	(wire
		(pts
			(xy 311.15 86.36) (xy 322.58 86.36)
		)
		(stroke
			(width 0)
			(type default)
		)
	)
	(wire
		(pts
			(xy 114.3 36.83) (xy 109.22 36.83)
		)
		(stroke
			(width 0)
			(type default)
		)
	)
	(wire
		(pts
			(xy 109.22 189.23) (xy 144.78 189.23)
		)
		(stroke
			(width 0)
			(type default)
		)
	)
	(wire
		(pts
			(xy 83.82 60.96) (xy 100.33 60.96)
		)
		(stroke
			(width 0)
			(type default)
		)
	)
	(polyline
		(pts
			(xy 185.42 245.11) (xy 185.42 285.75)
		)
		(stroke
			(width 0)
			(type default)
		)
	)
	(wire
		(pts
			(xy 148.59 260.35) (xy 153.67 260.35)
		)
		(stroke
			(width 0)
			(type default)
		)
	)
	(wire
		(pts
			(xy 354.33 129.54) (xy 354.33 133.35)
		)
		(stroke
			(width 0)
			(type default)
		)
	)
	(polyline
		(pts
			(xy 127 85.09) (xy 128.27 85.09)
		)
		(stroke
			(width 0)
			(type default)
		)
	)
	(wire
		(pts
			(xy 71.12 269.24) (xy 78.74 269.24)
		)
		(stroke
			(width 0)
			(type default)
		)
	)
	(bus
		(pts
			(xy 35.56 182.88) (xy 35.56 184.15)
		)
		(stroke
			(width 0)
			(type default)
		)
	)
	(wire
		(pts
			(xy 204.47 266.7) (xy 222.25 266.7)
		)
		(stroke
			(width 0)
			(type default)
		)
	)
	(wire
		(pts
			(xy 326.39 234.95) (xy 350.52 234.95)
		)
		(stroke
			(width 0)
			(type default)
		)
	)
	(wire
		(pts
			(xy 163.83 101.6) (xy 163.83 95.25)
		)
		(stroke
			(width 0)
			(type default)
		)
	)
	(wire
		(pts
			(xy 389.89 76.2) (xy 389.89 91.44)
		)
		(stroke
			(width 0)
			(type default)
		)
	)
	(bus
		(pts
			(xy 320.04 162.56) (xy 320.04 165.1)
		)
		(stroke
			(width 0)
			(type default)
		)
	)
	(wire
		(pts
			(xy 114.3 274.32) (xy 109.22 274.32)
		)
		(stroke
			(width 0)
			(type default)
		)
	)
	(wire
		(pts
			(xy 158.75 260.35) (xy 153.67 260.35)
		)
		(stroke
			(width 0)
			(type default)
		)
	)
	(wire
		(pts
			(xy 27.94 259.08) (xy 27.94 261.62)
		)
		(stroke
			(width 0)
			(type default)
		)
	)
	(wire
		(pts
			(xy 119.38 106.68) (xy 114.3 106.68)
		)
		(stroke
			(width 0)
			(type default)
		)
	)
	(wire
		(pts
			(xy 39.37 261.62) (xy 66.04 261.62)
		)
		(stroke
			(width 0)
			(type default)
		)
	)
	(wire
		(pts
			(xy 308.61 31.75) (xy 311.15 31.75)
		)
		(stroke
			(width 0)
			(type default)
		)
	)
	(wire
		(pts
			(xy 34.29 274.32) (xy 27.94 274.32)
		)
		(stroke
			(width 0)
			(type default)
		)
	)
	(wire
		(pts
			(xy 60.96 170.18) (xy 81.28 170.18)
		)
		(stroke
			(width 0)
			(type default)
		)
	)
	(wire
		(pts
			(xy 306.07 58.42) (xy 370.84 58.42)
		)
		(stroke
			(width 0)
			(type default)
		)
	)
	(polyline
		(pts
			(xy 12.7 138.43) (xy 271.78 138.43)
		)
		(stroke
			(width 0.5)
			(type default)
		)
	)
	(wire
		(pts
			(xy 341.63 196.85) (xy 325.12 196.85)
		)
		(stroke
			(width 0)
			(type default)
		)
	)
	(wire
		(pts
			(xy 144.78 185.42) (xy 144.78 189.23)
		)
		(stroke
			(width 0)
			(type default)
		)
	)
	(wire
		(pts
			(xy 55.88 77.47) (xy 55.88 78.74)
		)
		(stroke
			(width 0)
			(type default)
		)
	)
	(wire
		(pts
			(xy 163.83 210.82) (xy 163.83 215.9)
		)
		(stroke
			(width 0)
			(type default)
		)
	)
	(wire
		(pts
			(xy 57.15 233.68) (xy 57.15 234.95)
		)
		(stroke
			(width 0)
			(type default)
		)
	)
	(bus
		(pts
			(xy 41.91 40.64) (xy 44.45 40.64)
		)
		(stroke
			(width 0)
			(type default)
		)
	)
	(bus
		(pts
			(xy 35.56 189.23) (xy 35.56 190.5)
		)
		(stroke
			(width 0)
			(type default)
		)
	)
	(wire
		(pts
			(xy 34.29 276.86) (xy 27.94 276.86)
		)
		(stroke
			(width 0)
			(type default)
		)
	)
	(wire
		(pts
			(xy 349.25 245.11) (xy 349.25 246.38)
		)
		(stroke
			(width 0)
			(type default)
		)
	)
	(wire
		(pts
			(xy 163.83 264.16) (xy 163.83 260.35)
		)
		(stroke
			(width 0)
			(type default)
		)
	)
	(wire
		(pts
			(xy 370.84 88.9) (xy 391.16 88.9)
		)
		(stroke
			(width 0)
			(type default)
		)
	)
	(wire
		(pts
			(xy 34.29 266.7) (xy 27.94 266.7)
		)
		(stroke
			(width 0)
			(type default)
		)
	)
	(wire
		(pts
			(xy 49.53 175.26) (xy 49.53 163.83)
		)
		(stroke
			(width 0)
			(type default)
		)
	)
	(wire
		(pts
			(xy 334.01 93.98) (xy 334.01 95.25)
		)
		(stroke
			(width 0)
			(type default)
		)
	)
	(wire
		(pts
			(xy 55.88 224.79) (xy 57.15 224.79)
		)
		(stroke
			(width 0)
			(type default)
		)
	)
	(wire
		(pts
			(xy 243.84 205.74) (xy 245.11 205.74)
		)
		(stroke
			(width 0)
			(type default)
		)
	)
	(wire
		(pts
			(xy 250.19 220.98) (xy 254 220.98)
		)
		(stroke
			(width 0)
			(type default)
		)
	)
	(wire
		(pts
			(xy 133.35 167.64) (xy 109.22 167.64)
		)
		(stroke
			(width 0)
			(type default)
		)
	)
	(wire
		(pts
			(xy 328.93 31.75) (xy 328.93 33.02)
		)
		(stroke
			(width 0)
			(type default)
		)
	)
	(wire
		(pts
			(xy 191.77 215.9) (xy 194.31 215.9)
		)
		(stroke
			(width 0)
			(type default)
		)
	)
	(bus
		(pts
			(xy 58.42 162.56) (xy 58.42 165.1)
		)
		(stroke
			(width 0)
			(type default)
		)
	)
	(wire
		(pts
			(xy 163.83 85.09) (xy 180.34 85.09)
		)
		(stroke
			(width 0)
			(type default)
		)
	)
	(wire
		(pts
			(xy 34.29 269.24) (xy 27.94 269.24)
		)
		(stroke
			(width 0)
			(type default)
		)
	)
	(wire
		(pts
			(xy 341.63 96.52) (xy 391.16 96.52)
		)
		(stroke
			(width 0)
			(type default)
		)
	)
	(wire
		(pts
			(xy 71.12 261.62) (xy 78.74 261.62)
		)
		(stroke
			(width 0)
			(type default)
		)
	)
	(wire
		(pts
			(xy 326.39 240.03) (xy 350.52 240.03)
		)
		(stroke
			(width 0)
			(type default)
		)
	)
	(wire
		(pts
			(xy 81.28 213.36) (xy 66.04 213.36)
		)
		(stroke
			(width 0)
			(type default)
		)
	)
	(wire
		(pts
			(xy 261.62 213.36) (xy 261.62 220.98)
		)
		(stroke
			(width 0)
			(type default)
		)
	)
	(wire
		(pts
			(xy 41.91 175.26) (xy 41.91 163.83)
		)
		(stroke
			(width 0)
			(type default)
		)
	)
	(bus
		(pts
			(xy 303.53 63.5) (xy 303.53 68.58)
		)
		(stroke
			(width 0)
			(type default)
		)
	)
	(wire
		(pts
			(xy 386.08 45.72) (xy 386.08 50.8)
		)
		(stroke
			(width 0)
			(type default)
		)
	)
	(wire
		(pts
			(xy 109.22 162.56) (xy 133.35 162.56)
		)
		(stroke
			(width 0)
			(type default)
		)
	)
	(wire
		(pts
			(xy 46.99 163.83) (xy 49.53 163.83)
		)
		(stroke
			(width 0)
			(type default)
		)
	)
	(wire
		(pts
			(xy 48.26 36.83) (xy 48.26 40.64)
		)
		(stroke
			(width 0)
			(type default)
		)
	)
	(wire
		(pts
			(xy 243.84 213.36) (xy 245.11 213.36)
		)
		(stroke
			(width 0)
			(type default)
		)
	)
	(wire
		(pts
			(xy 148.59 80.01) (xy 191.77 80.01)
		)
		(stroke
			(width 0)
			(type default)
		)
	)
	(wire
		(pts
			(xy 370.84 31.75) (xy 378.46 31.75)
		)
		(stroke
			(width 0)
			(type default)
		)
	)
	(wire
		(pts
			(xy 195.58 167.64) (xy 218.44 167.64)
		)
		(stroke
			(width 0)
			(type default)
		)
	)
	(wire
		(pts
			(xy 81.28 215.9) (xy 66.04 215.9)
		)
		(stroke
			(width 0)
			(type default)
		)
	)
	(wire
		(pts
			(xy 177.8 54.61) (xy 177.8 53.34)
		)
		(stroke
			(width 0)
			(type default)
		)
	)
	(wire
		(pts
			(xy 27.94 274.32) (xy 27.94 276.86)
		)
		(stroke
			(width 0)
			(type default)
		)
	)
	(wire
		(pts
			(xy 254 229.87) (xy 250.19 229.87)
		)
		(stroke
			(width 0)
			(type default)
		)
	)
	(bus
		(pts
			(xy 317.5 160.02) (xy 318.77 160.02)
		)
		(stroke
			(width 0)
			(type default)
		)
	)
	(wire
		(pts
			(xy 328.93 45.72) (xy 328.93 78.74)
		)
		(stroke
			(width 0)
			(type default)
		)
	)
	(wire
		(pts
			(xy 220.98 276.86) (xy 220.98 275.59)
		)
		(stroke
			(width 0)
			(type default)
		)
	)
	(wire
		(pts
			(xy 44.45 163.83) (xy 46.99 163.83)
		)
		(stroke
			(width 0)
			(type default)
		)
	)
	(wire
		(pts
			(xy 29.21 161.29) (xy 29.21 163.83)
		)
		(stroke
			(width 0)
			(type default)
		)
	)
	(wire
		(pts
			(xy 365.76 93.98) (xy 365.76 125.73)
		)
		(stroke
			(width 0)
			(type default)
		)
	)
	(wire
		(pts
			(xy 345.44 31.75) (xy 345.44 33.02)
		)
		(stroke
			(width 0)
			(type default)
		)
	)
	(wire
		(pts
			(xy 158.75 260.35) (xy 163.83 260.35)
		)
		(stroke
			(width 0)
			(type default)
		)
	)
	(wire
		(pts
			(xy 287.02 233.68) (xy 308.61 233.68)
		)
		(stroke
			(width 0)
			(type default)
		)
	)
	(wire
		(pts
			(xy 300.99 104.14) (xy 300.99 105.41)
		)
		(stroke
			(width 0)
			(type default)
		)
	)
	(wire
		(pts
			(xy 358.14 200.66) (xy 379.73 200.66)
		)
		(stroke
			(width 0)
			(type default)
		)
	)
	(bus
		(pts
			(xy 58.42 175.26) (xy 58.42 177.8)
		)
		(stroke
			(width 0)
			(type default)
		)
	)
	(wire
		(pts
			(xy 168.91 260.35) (xy 163.83 260.35)
		)
		(stroke
			(width 0)
			(type default)
		)
	)
	(wire
		(pts
			(xy 27.94 269.24) (xy 27.94 271.78)
		)
		(stroke
			(width 0)
			(type default)
		)
	)
	(wire
		(pts
			(xy 81.28 220.98) (xy 66.04 220.98)
		)
		(stroke
			(width 0)
			(type default)
		)
	)
	(wire
		(pts
			(xy 34.29 115.57) (xy 34.29 114.3)
		)
		(stroke
			(width 0)
			(type default)
		)
	)
	(wire
		(pts
			(xy 78.74 274.32) (xy 78.74 276.86)
		)
		(stroke
			(width 0)
			(type default)
		)
	)
	(wire
		(pts
			(xy 325.12 93.98) (xy 325.12 104.14)
		)
		(stroke
			(width 0)
			(type default)
		)
	)
	(wire
		(pts
			(xy 325.12 104.14) (xy 326.39 104.14)
		)
		(stroke
			(width 0)
			(type default)
		)
	)
	(wire
		(pts
			(xy 195.58 180.34) (xy 218.44 180.34)
		)
		(stroke
			(width 0)
			(type default)
		)
	)
	(wire
		(pts
			(xy 353.06 45.72) (xy 353.06 66.04)
		)
		(stroke
			(width 0)
			(type default)
		)
	)
	(wire
		(pts
			(xy 171.45 215.9) (xy 182.88 215.9)
		)
		(stroke
			(width 0)
			(type default)
		)
	)
	(wire
		(pts
			(xy 261.62 229.87) (xy 259.08 229.87)
		)
		(stroke
			(width 0)
			(type default)
		)
	)
	(wire
		(pts
			(xy 133.35 177.8) (xy 109.22 177.8)
		)
		(stroke
			(width 0)
			(type default)
		)
	)
	(wire
		(pts
			(xy 359.41 154.94) (xy 369.57 154.94)
		)
		(stroke
			(width 0)
			(type default)
		)
	)
	(polyline
		(pts
			(xy 273.05 219.71) (xy 407.67 219.71)
		)
		(stroke
			(width 0.5)
			(type default)
		)
	)
	(wire
		(pts
			(xy 326.39 237.49) (xy 350.52 237.49)
		)
		(stroke
			(width 0)
			(type default)
		)
	)
	(wire
		(pts
			(xy 140.97 180.34) (xy 140.97 179.07)
		)
		(stroke
			(width 0)
			(type default)
		)
	)
	(wire
		(pts
			(xy 386.08 245.11) (xy 386.08 243.84)
		)
		(stroke
			(width 0)
			(type default)
		)
	)
	(wire
		(pts
			(xy 114.3 274.32) (xy 119.38 274.32)
		)
		(stroke
			(width 0)
			(type default)
		)
	)
	(wire
		(pts
			(xy 287.02 241.3) (xy 308.61 241.3)
		)
		(stroke
			(width 0)
			(type default)
		)
	)
	(wire
		(pts
			(xy 118.11 184.15) (xy 133.35 184.15)
		)
		(stroke
			(width 0)
			(type default)
		)
	)
	(wire
		(pts
			(xy 358.14 165.1) (xy 375.92 165.1)
		)
		(stroke
			(width 0)
			(type default)
		)
	)
	(wire
		(pts
			(xy 140.97 185.42) (xy 140.97 186.69)
		)
		(stroke
			(width 0)
			(type default)
		)
	)
	(wire
		(pts
			(xy 358.14 203.2) (xy 379.73 203.2)
		)
		(stroke
			(width 0)
			(type default)
		)
	)
	(wire
		(pts
			(xy 48.26 40.64) (xy 64.77 40.64)
		)
		(stroke
			(width 0)
			(type default)
		)
	)
	(wire
		(pts
			(xy 311.15 31.75) (xy 320.04 31.75)
		)
		(stroke
			(width 0)
			(type default)
		)
	)
	(wire
		(pts
			(xy 334.01 93.98) (xy 341.63 93.98)
		)
		(stroke
			(width 0)
			(type default)
		)
	)
	(wire
		(pts
			(xy 137.16 260.35) (xy 148.59 260.35)
		)
		(stroke
			(width 0)
			(type default)
		)
	)
	(wire
		(pts
			(xy 238.76 275.59) (xy 237.49 275.59)
		)
		(stroke
			(width 0)
			(type default)
		)
	)
	(wire
		(pts
			(xy 90.17 106.68) (xy 90.17 113.03)
		)
		(stroke
			(width 0)
			(type default)
		)
	)
	(wire
		(pts
			(xy 261.62 229.87) (xy 261.62 232.41)
		)
		(stroke
			(width 0)
			(type default)
		)
	)
	(wire
		(pts
			(xy 48.26 115.57) (xy 54.61 115.57)
		)
		(stroke
			(width 0)
			(type default)
		)
	)
	(wire
		(pts
			(xy 191.77 85.09) (xy 185.42 85.09)
		)
		(stroke
			(width 0)
			(type default)
		)
	)
	(wire
		(pts
			(xy 250.19 215.9) (xy 250.19 220.98)
		)
		(stroke
			(width 0)
			(type default)
		)
	)
	(wire
		(pts
			(xy 234.95 91.44) (xy 232.41 91.44)
		)
		(stroke
			(width 0)
			(type default)
		)
	)
	(wire
		(pts
			(xy 389.89 91.44) (xy 391.16 91.44)
		)
		(stroke
			(width 0)
			(type default)
		)
	)
	(wire
		(pts
			(xy 361.95 45.72) (xy 361.95 63.5)
		)
		(stroke
			(width 0)
			(type default)
		)
	)
	(wire
		(pts
			(xy 48.26 53.34) (xy 64.77 53.34)
		)
		(stroke
			(width 0)
			(type default)
		)
	)
	(wire
		(pts
			(xy 34.29 107.95) (xy 34.29 109.22)
		)
		(stroke
			(width 0)
			(type default)
		)
	)
	(bus
		(pts
			(xy 303.53 45.72) (xy 303.53 48.26)
		)
		(stroke
			(width 0)
			(type default)
		)
	)
	(wire
		(pts
			(xy 194.31 215.9) (xy 201.93 215.9)
		)
		(stroke
			(width 0)
			(type default)
		)
	)
	(wire
		(pts
			(xy 353.06 66.04) (xy 391.16 66.04)
		)
		(stroke
			(width 0)
			(type default)
		)
	)
	(wire
		(pts
			(xy 158.75 264.16) (xy 158.75 260.35)
		)
		(stroke
			(width 0)
			(type default)
		)
	)
	(wire
		(pts
			(xy 353.06 38.1) (xy 353.06 40.64)
		)
		(stroke
			(width 0)
			(type default)
		)
	)
	(wire
		(pts
			(xy 378.46 45.72) (xy 378.46 55.88)
		)
		(stroke
			(width 0)
			(type default)
		)
	)
	(wire
		(pts
			(xy 158.75 274.32) (xy 153.67 274.32)
		)
		(stroke
			(width 0)
			(type default)
		)
	)
	(wire
		(pts
			(xy 220.98 270.51) (xy 220.98 273.05)
		)
		(stroke
			(width 0)
			(type default)
		)
	)
	(wire
		(pts
			(xy 261.62 213.36) (xy 245.11 213.36)
		)
		(stroke
			(width 0)
			(type default)
		)
	)
	(wire
		(pts
			(xy 129.54 257.81) (xy 129.54 260.35)
		)
		(stroke
			(width 0)
			(type default)
		)
	)
	(wire
		(pts
			(xy 387.35 158.75) (xy 397.51 158.75)
		)
		(stroke
			(width 0)
			(type default)
		)
	)
	(wire
		(pts
			(xy 182.88 215.9) (xy 186.69 215.9)
		)
		(stroke
			(width 0)
			(type default)
		)
	)
	(wire
		(pts
			(xy 163.83 215.9) (xy 166.37 215.9)
		)
		(stroke
			(width 0)
			(type default)
		)
	)
	(wire
		(pts
			(xy 168.91 274.32) (xy 163.83 274.32)
		)
		(stroke
			(width 0)
			(type default)
		)
	)
	(wire
		(pts
			(xy 250.19 229.87) (xy 250.19 220.98)
		)
		(stroke
			(width 0)
			(type default)
		)
	)
	(wire
		(pts
			(xy 60.96 167.64) (xy 81.28 167.64)
		)
		(stroke
			(width 0)
			(type default)
		)
	)
	(wire
		(pts
			(xy 137.16 257.81) (xy 137.16 260.35)
		)
		(stroke
			(width 0)
			(type default)
		)
	)
	(bus
		(pts
			(xy 299.72 44.45) (xy 302.26 44.45)
		)
		(stroke
			(width 0)
			(type default)
		)
	)
	(wire
		(pts
			(xy 334.01 110.49) (xy 334.01 107.95)
		)
		(stroke
			(width 0)
			(type default)
		)
	)
	(wire
		(pts
			(xy 34.29 271.78) (xy 27.94 271.78)
		)
		(stroke
			(width 0)
			(type default)
		)
	)
	(bus
		(pts
			(xy 303.53 60.96) (xy 303.53 63.5)
		)
		(stroke
			(width 0)
			(type default)
		)
	)
	(wire
		(pts
			(xy 87.63 115.57) (xy 102.87 115.57)
		)
		(stroke
			(width 0)
			(type default)
		)
	)
	(wire
		(pts
			(xy 261.62 220.98) (xy 259.08 220.98)
		)
		(stroke
			(width 0)
			(type default)
		)
	)
	(bus
		(pts
			(xy 34.29 187.96) (xy 35.56 189.23)
		)
		(stroke
			(width 0)
			(type default)
		)
	)
	(wire
		(pts
			(xy 119.38 264.16) (xy 119.38 260.35)
		)
		(stroke
			(width 0)
			(type default)
		)
	)
	(wire
		(pts
			(xy 389.89 60.96) (xy 389.89 68.58)
		)
		(stroke
			(width 0)
			(type default)
		)
	)
	(wire
		(pts
			(xy 41.91 180.34) (xy 41.91 186.69)
		)
		(stroke
			(width 0)
			(type default)
		)
	)
	(wire
		(pts
			(xy 38.1 195.58) (xy 49.53 195.58)
		)
		(stroke
			(width 0)
			(type default)
		)
	)
	(wire
		(pts
			(xy 85.09 66.04) (xy 83.82 66.04)
		)
		(stroke
			(width 0)
			(type default)
		)
	)
	(wire
		(pts
			(xy 234.95 93.98) (xy 234.95 91.44)
		)
		(stroke
			(width 0)
			(type default)
		)
	)
	(wire
		(pts
			(xy 39.37 264.16) (xy 66.04 264.16)
		)
		(stroke
			(width 0)
			(type default)
		)
	)
	(wire
		(pts
			(xy 163.83 274.32) (xy 163.83 269.24)
		)
		(stroke
			(width 0)
			(type default)
		)
	)
	(wire
		(pts
			(xy 81.28 210.82) (xy 66.04 210.82)
		)
		(stroke
			(width 0)
			(type default)
		)
	)
	(wire
		(pts
			(xy 114.3 116.84) (xy 114.3 115.57)
		)
		(stroke
			(width 0)
			(type default)
		)
	)
	(wire
		(pts
			(xy 370.84 58.42) (xy 391.16 58.42)
		)
		(stroke
			(width 0)
			(type default)
		)
	)
	(wire
		(pts
			(xy 288.29 158.75) (xy 288.29 160.02)
		)
		(stroke
			(width 0)
			(type default)
		)
	)
	(wire
		(pts
			(xy 21.59 115.57) (xy 21.59 114.3)
		)
		(stroke
			(width 0)
			(type default)
		)
	)
	(wire
		(pts
			(xy 87.63 120.65) (xy 90.17 120.65)
		)
		(stroke
			(width 0)
			(type default)
		)
	)
	(wire
		(pts
			(xy 322.58 167.64) (xy 340.36 167.64)
		)
		(stroke
			(width 0)
			(type default)
		)
	)
	(wire
		(pts
			(xy 102.87 115.57) (xy 102.87 114.3)
		)
		(stroke
			(width 0)
			(type default)
		)
	)
	(wire
		(pts
			(xy 148.59 85.09) (xy 163.83 85.09)
		)
		(stroke
			(width 0)
			(type default)
		)
	)
	(wire
		(pts
			(xy 137.16 251.46) (xy 137.16 252.73)
		)
		(stroke
			(width 0)
			(type default)
		)
	)
	(wire
		(pts
			(xy 60.96 162.56) (xy 81.28 162.56)
		)
		(stroke
			(width 0)
			(type default)
		)
	)
	(wire
		(pts
			(xy 389.89 68.58) (xy 391.16 68.58)
		)
		(stroke
			(width 0)
			(type default)
		)
	)
	(wire
		(pts
			(xy 133.35 175.26) (xy 109.22 175.26)
		)
		(stroke
			(width 0)
			(type default)
		)
	)
	(bus
		(pts
			(xy 35.56 184.15) (xy 35.56 186.69)
		)
		(stroke
			(width 0)
			(type default)
		)
	)
	(wire
		(pts
			(xy 140.97 179.07) (xy 144.78 179.07)
		)
		(stroke
			(width 0)
			(type default)
		)
	)
	(wire
		(pts
			(xy 76.2 182.88) (xy 80.01 182.88)
		)
		(stroke
			(width 0)
			(type default)
		)
	)
	(wire
		(pts
			(xy 144.78 176.53) (xy 144.78 179.07)
		)
		(stroke
			(width 0)
			(type default)
		)
	)
	(wire
		(pts
			(xy 41.91 163.83) (xy 44.45 163.83)
		)
		(stroke
			(width 0)
			(type default)
		)
	)
	(bus
		(pts
			(xy 34.29 181.61) (xy 35.56 182.88)
		)
		(stroke
			(width 0)
			(type default)
		)
	)
	(wire
		(pts
			(xy 361.95 31.75) (xy 361.95 33.02)
		)
		(stroke
			(width 0)
			(type default)
		)
	)
	(wire
		(pts
			(xy 78.74 271.78) (xy 78.74 274.32)
		)
		(stroke
			(width 0)
			(type default)
		)
	)
	(wire
		(pts
			(xy 114.3 260.35) (xy 119.38 260.35)
		)
		(stroke
			(width 0)
			(type default)
		)
	)
	(wire
		(pts
			(xy 370.84 236.22) (xy 387.35 236.22)
		)
		(stroke
			(width 0)
			(type default)
		)
	)
	(wire
		(pts
			(xy 173.99 269.24) (xy 173.99 274.32)
		)
		(stroke
			(width 0)
			(type default)
		)
	)
	(wire
		(pts
			(xy 245.11 208.28) (xy 245.11 210.82)
		)
		(stroke
			(width 0)
			(type default)
		)
	)
	(wire
		(pts
			(xy 60.96 175.26) (xy 81.28 175.26)
		)
		(stroke
			(width 0)
			(type default)
		)
	)
	(wire
		(pts
			(xy 311.15 110.49) (xy 311.15 107.95)
		)
		(stroke
			(width 0)
			(type default)
		)
	)
	(wire
		(pts
			(xy 389.89 60.96) (xy 391.16 60.96)
		)
		(stroke
			(width 0)
			(type default)
		)
	)
	(wire
		(pts
			(xy 242.57 264.16) (xy 242.57 265.43)
		)
		(stroke
			(width 0)
			(type default)
		)
	)
	(wire
		(pts
			(xy 48.26 60.96) (xy 64.77 60.96)
		)
		(stroke
			(width 0)
			(type default)
		)
	)
	(wire
		(pts
			(xy 46.99 180.34) (xy 46.99 193.04)
		)
		(stroke
			(width 0)
			(type default)
		)
	)
	(wire
		(pts
			(xy 39.37 269.24) (xy 66.04 269.24)
		)
		(stroke
			(width 0)
			(type default)
		)
	)
	(wire
		(pts
			(xy 306.07 63.5) (xy 361.95 63.5)
		)
		(stroke
			(width 0)
			(type default)
		)
	)
	(polyline
		(pts
			(xy 271.78 138.43) (xy 408.94 138.43)
		)
		(stroke
			(width 0)
			(type default)
		)
	)
	(wire
		(pts
			(xy 54.61 115.57) (xy 69.85 115.57)
		)
		(stroke
			(width 0)
			(type default)
		)
	)
	(wire
		(pts
			(xy 114.3 106.68) (xy 114.3 110.49)
		)
		(stroke
			(width 0)
			(type default)
		)
	)
	(wire
		(pts
			(xy 238.76 276.86) (xy 238.76 275.59)
		)
		(stroke
			(width 0)
			(type default)
		)
	)
	(wire
		(pts
			(xy 378.46 31.75) (xy 386.08 31.75)
		)
		(stroke
			(width 0)
			(type default)
		)
	)
	(wire
		(pts
			(xy 311.15 92.71) (xy 311.15 93.98)
		)
		(stroke
			(width 0)
			(type default)
		)
	)
	(wire
		(pts
			(xy 133.35 170.18) (xy 109.22 170.18)
		)
		(stroke
			(width 0)
			(type default)
		)
	)
	(wire
		(pts
			(xy 83.82 40.64) (xy 100.33 40.64)
		)
		(stroke
			(width 0)
			(type default)
		)
	)
	(wire
		(pts
			(xy 361.95 63.5) (xy 391.16 63.5)
		)
		(stroke
			(width 0)
			(type default)
		)
	)
	(wire
		(pts
			(xy 39.37 266.7) (xy 66.04 266.7)
		)
		(stroke
			(width 0)
			(type default)
		)
	)
	(wire
		(pts
			(xy 29.21 163.83) (xy 41.91 163.83)
		)
		(stroke
			(width 0)
			(type default)
		)
	)
	(wire
		(pts
			(xy 306.07 66.04) (xy 353.06 66.04)
		)
		(stroke
			(width 0)
			(type default)
		)
	)
	(wire
		(pts
			(xy 370.84 86.36) (xy 391.16 86.36)
		)
		(stroke
			(width 0)
			(type default)
		)
	)
	(wire
		(pts
			(xy 386.08 50.8) (xy 391.16 50.8)
		)
		(stroke
			(width 0)
			(type default)
		)
	)
	(wire
		(pts
			(xy 48.26 111.76) (xy 48.26 115.57)
		)
		(stroke
			(width 0)
			(type default)
		)
	)
	(bus
		(pts
			(xy 45.72 55.88) (xy 45.72 58.42)
		)
		(stroke
			(width 0)
			(type default)
		)
	)
	(wire
		(pts
			(xy 39.37 276.86) (xy 66.04 276.86)
		)
		(stroke
			(width 0)
			(type default)
		)
	)
	(wire
		(pts
			(xy 340.36 204.47) (xy 341.63 204.47)
		)
		(stroke
			(width 0)
			(type default)
		)
	)
	(wire
		(pts
			(xy 290.83 200.66) (xy 307.34 200.66)
		)
		(stroke
			(width 0)
			(type default)
		)
	)
	(wire
		(pts
			(xy 361.95 38.1) (xy 361.95 40.64)
		)
		(stroke
			(width 0)
			(type default)
		)
	)
	(wire
		(pts
			(xy 38.1 189.23) (xy 44.45 189.23)
		)
		(stroke
			(width 0)
			(type default)
		)
	)
	(wire
		(pts
			(xy 328.93 38.1) (xy 328.93 40.64)
		)
		(stroke
			(width 0)
			(type default)
		)
	)
	(wire
		(pts
			(xy 354.33 93.98) (xy 365.76 93.98)
		)
		(stroke
			(width 0)
			(type default)
		)
	)
	(wire
		(pts
			(xy 69.85 118.11) (xy 66.04 118.11)
		)
		(stroke
			(width 0)
			(type default)
		)
	)
	(wire
		(pts
			(xy 109.22 165.1) (xy 133.35 165.1)
		)
		(stroke
			(width 0)
			(type default)
		)
	)
	(wire
		(pts
			(xy 287.02 238.76) (xy 308.61 238.76)
		)
		(stroke
			(width 0)
			(type default)
		)
	)
	(wire
		(pts
			(xy 353.06 31.75) (xy 361.95 31.75)
		)
		(stroke
			(width 0)
			(type default)
		)
	)
	(wire
		(pts
			(xy 322.58 165.1) (xy 340.36 165.1)
		)
		(stroke
			(width 0)
			(type default)
		)
	)
	(wire
		(pts
			(xy 288.29 165.1) (xy 288.29 166.37)
		)
		(stroke
			(width 0)
			(type default)
		)
	)
	(wire
		(pts
			(xy 325.12 199.39) (xy 341.63 199.39)
		)
		(stroke
			(width 0)
			(type default)
		)
	)
	(wire
		(pts
			(xy 109.22 186.69) (xy 140.97 186.69)
		)
		(stroke
			(width 0)
			(type default)
		)
	)
	(wire
		(pts
			(xy 354.33 107.95) (xy 354.33 116.84)
		)
		(stroke
			(width 0)
			(type default)
		)
	)
	(bus
		(pts
			(xy 44.45 40.64) (xy 45.72 41.91)
		)
		(stroke
			(width 0)
			(type default)
		)
	)
	(wire
		(pts
			(xy 148.59 72.39) (xy 191.77 72.39)
		)
		(stroke
			(width 0)
			(type default)
		)
	)
	(wire
		(pts
			(xy 133.35 172.72) (xy 109.22 172.72)
		)
		(stroke
			(width 0)
			(type default)
		)
	)
	(wire
		(pts
			(xy 220.98 273.05) (xy 222.25 273.05)
		)
		(stroke
			(width 0)
			(type default)
		)
	)
	(wire
		(pts
			(xy 83.82 48.26) (xy 100.33 48.26)
		)
		(stroke
			(width 0)
			(type default)
		)
	)
	(wire
		(pts
			(xy 48.26 58.42) (xy 64.77 58.42)
		)
		(stroke
			(width 0)
			(type default)
		)
	)
	(wire
		(pts
			(xy 261.62 229.87) (xy 261.62 220.98)
		)
		(stroke
			(width 0)
			(type default)
		)
	)
	(wire
		(pts
			(xy 38.1 186.69) (xy 41.91 186.69)
		)
		(stroke
			(width 0)
			(type default)
		)
	)
	(wire
		(pts
			(xy 370.84 45.72) (xy 370.84 58.42)
		)
		(stroke
			(width 0)
			(type default)
		)
	)
	(wire
		(pts
			(xy 80.01 153.67) (xy 80.01 156.21)
		)
		(stroke
			(width 0)
			(type default)
		)
	)
	(wire
		(pts
			(xy 306.07 73.66) (xy 336.55 73.66)
		)
		(stroke
			(width 0)
			(type default)
		)
	)
	(wire
		(pts
			(xy 158.75 274.32) (xy 163.83 274.32)
		)
		(stroke
			(width 0)
			(type default)
		)
	)
	(wire
		(pts
			(xy 245.11 203.2) (xy 245.11 205.74)
		)
		(stroke
			(width 0)
			(type default)
		)
	)
	(wire
		(pts
			(xy 386.08 38.1) (xy 386.08 40.64)
		)
		(stroke
			(width 0)
			(type default)
		)
	)
	(wire
		(pts
			(xy 287.02 236.22) (xy 308.61 236.22)
		)
		(stroke
			(width 0)
			(type default)
		)
	)
	(wire
		(pts
			(xy 361.95 31.75) (xy 370.84 31.75)
		)
		(stroke
			(width 0)
			(type default)
		)
	)
	(wire
		(pts
			(xy 245.11 210.82) (xy 245.11 213.36)
		)
		(stroke
			(width 0)
			(type default)
		)
	)
	(wire
		(pts
			(xy 359.41 162.56) (xy 359.41 154.94)
		)
		(stroke
			(width 0)
			(type default)
		)
	)
	(bus
		(pts
			(xy 45.72 53.34) (xy 45.72 55.88)
		)
		(stroke
			(width 0)
			(type default)
		)
	)
	(wire
		(pts
			(xy 90.17 121.92) (xy 90.17 120.65)
		)
		(stroke
			(width 0)
			(type default)
		)
	)
	(polyline
		(pts
			(xy 273.05 138.43) (xy 273.05 219.71)
		)
		(stroke
			(width 0.5)
			(type default)
		)
	)
	(wire
		(pts
			(xy 238.76 269.24) (xy 238.76 275.59)
		)
		(stroke
			(width 0)
			(type default)
		)
	)
	(wire
		(pts
			(xy 27.94 266.7) (xy 27.94 269.24)
		)
		(stroke
			(width 0)
			(type default)
		)
	)
	(wire
		(pts
			(xy 306.07 55.88) (xy 378.46 55.88)
		)
		(stroke
			(width 0)
			(type default)
		)
	)
	(wire
		(pts
			(xy 311.15 95.25) (xy 311.15 93.98)
		)
		(stroke
			(width 0)
			(type default)
		)
	)
	(bus
		(pts
			(xy 33.02 181.61) (xy 34.29 181.61)
		)
		(stroke
			(width 0)
			(type default)
		)
	)
	(wire
		(pts
			(xy 295.91 116.84) (xy 354.33 116.84)
		)
		(stroke
			(width 0)
			(type default)
		)
	)
	(wire
		(pts
			(xy 71.12 276.86) (xy 78.74 276.86)
		)
		(stroke
			(width 0)
			(type default)
		)
	)
	(wire
		(pts
			(xy 311.15 86.36) (xy 311.15 87.63)
		)
		(stroke
			(width 0)
			(type default)
		)
	)
	(wire
		(pts
			(xy 173.99 275.59) (xy 173.99 274.32)
		)
		(stroke
			(width 0)
			(type default)
		)
	)
	(wire
		(pts
			(xy 308.61 243.84) (xy 307.34 243.84)
		)
		(stroke
			(width 0)
			(type default)
		)
	)
	(bus
		(pts
			(xy 57.15 157.48) (xy 58.42 158.75)
		)
		(stroke
			(width 0)
			(type default)
		)
	)
	(wire
		(pts
			(xy 200.66 208.28) (xy 218.44 208.28)
		)
		(stroke
			(width 0)
			(type default)
		)
	)
	(wire
		(pts
			(xy 201.93 214.63) (xy 201.93 215.9)
		)
		(stroke
			(width 0)
			(type default)
		)
	)
	(wire
		(pts
			(xy 365.76 125.73) (xy 361.95 125.73)
		)
		(stroke
			(width 0)
			(type default)
		)
	)
	(wire
		(pts
			(xy 114.3 264.16) (xy 114.3 260.35)
		)
		(stroke
			(width 0)
			(type default)
		)
	)
	(wire
		(pts
			(xy 80.01 184.15) (xy 81.28 184.15)
		)
		(stroke
			(width 0)
			(type default)
		)
	)
	(wire
		(pts
			(xy 173.99 264.16) (xy 173.99 260.35)
		)
		(stroke
			(width 0)
			(type default)
		)
	)
	(wire
		(pts
			(xy 109.22 274.32) (xy 109.22 269.24)
		)
		(stroke
			(width 0)
			(type default)
		)
	)
	(wire
		(pts
			(xy 195.58 182.88) (xy 218.44 182.88)
		)
		(stroke
			(width 0)
			(type default)
		)
	)
	(wire
		(pts
			(xy 39.37 274.32) (xy 66.04 274.32)
		)
		(stroke
			(width 0)
			(type default)
		)
	)
	(wire
		(pts
			(xy 83.82 55.88) (xy 100.33 55.88)
		)
		(stroke
			(width 0)
			(type default)
		)
	)
	(wire
		(pts
			(xy 341.63 93.98) (xy 349.25 93.98)
		)
		(stroke
			(width 0)
			(type default)
		)
	)
	(wire
		(pts
			(xy 299.72 31.75) (xy 303.53 31.75)
		)
		(stroke
			(width 0)
			(type default)
		)
	)
	(wire
		(pts
			(xy 168.91 264.16) (xy 168.91 260.35)
		)
		(stroke
			(width 0)
			(type default)
		)
	)
	(wire
		(pts
			(xy 54.61 115.57) (xy 54.61 120.65)
		)
		(stroke
			(width 0)
			(type default)
		)
	)
	(wire
		(pts
			(xy 339.09 170.18) (xy 339.09 162.56)
		)
		(stroke
			(width 0)
			(type default)
		)
	)
	(wire
		(pts
			(xy 389.89 53.34) (xy 389.89 48.26)
		)
		(stroke
			(width 0)
			(type default)
		)
	)
	(polyline
		(pts
			(xy 273.05 12.7) (xy 273.05 138.43)
		)
		(stroke
			(width 0.5)
			(type default)
		)
	)
	(wire
		(pts
			(xy 306.07 71.12) (xy 345.44 71.12)
		)
		(stroke
			(width 0)
			(type default)
		)
	)
	(wire
		(pts
			(xy 71.12 274.32) (xy 78.74 274.32)
		)
		(stroke
			(width 0)
			(type default)
		)
	)
	(bus
		(pts
			(xy 320.04 161.29) (xy 320.04 162.56)
		)
		(stroke
			(width 0)
			(type default)
		)
	)
	(wire
		(pts
			(xy 148.59 274.32) (xy 148.59 269.24)
		)
		(stroke
			(width 0)
			(type default)
		)
	)
	(wire
		(pts
			(xy 370.84 238.76) (xy 387.35 238.76)
		)
		(stroke
			(width 0)
			(type default)
		)
	)
	(wire
		(pts
			(xy 311.15 40.64) (xy 311.15 39.37)
		)
		(stroke
			(width 0)
			(type default)
		)
	)
	(wire
		(pts
			(xy 34.29 264.16) (xy 27.94 264.16)
		)
		(stroke
			(width 0)
			(type default)
		)
	)
	(wire
		(pts
			(xy 306.07 78.74) (xy 328.93 78.74)
		)
		(stroke
			(width 0)
			(type default)
		)
	)
	(polyline
		(pts
			(xy 158.75 138.43) (xy 158.75 245.11)
		)
		(stroke
			(width 0)
			(type default)
		)
	)
	(wire
		(pts
			(xy 358.14 167.64) (xy 375.92 167.64)
		)
		(stroke
			(width 0)
			(type default)
		)
	)
	(bus
		(pts
			(xy 54.61 157.48) (xy 57.15 157.48)
		)
		(stroke
			(width 0)
			(type default)
		)
	)
	(wire
		(pts
			(xy 168.91 260.35) (xy 173.99 260.35)
		)
		(stroke
			(width 0)
			(type default)
		)
	)
	(wire
		(pts
			(xy 114.3 43.18) (xy 114.3 44.45)
		)
		(stroke
			(width 0)
			(type default)
		)
	)
	(wire
		(pts
			(xy 182.88 210.82) (xy 182.88 215.9)
		)
		(stroke
			(width 0)
			(type default)
		)
	)
	(wire
		(pts
			(xy 38.1 193.04) (xy 46.99 193.04)
		)
		(stroke
			(width 0)
			(type default)
		)
	)
	(wire
		(pts
			(xy 41.91 186.69) (xy 81.28 186.69)
		)
		(stroke
			(width 0)
			(type default)
		)
	)
	(wire
		(pts
			(xy 195.58 190.5) (xy 218.44 190.5)
		)
		(stroke
			(width 0)
			(type default)
		)
	)
	(wire
		(pts
			(xy 71.12 271.78) (xy 78.74 271.78)
		)
		(stroke
			(width 0)
			(type default)
		)
	)
	(wire
		(pts
			(xy 204.47 264.16) (xy 222.25 264.16)
		)
		(stroke
			(width 0)
			(type default)
		)
	)
	(wire
		(pts
			(xy 336.55 31.75) (xy 345.44 31.75)
		)
		(stroke
			(width 0)
			(type default)
		)
	)
	(wire
		(pts
			(xy 27.94 261.62) (xy 27.94 264.16)
		)
		(stroke
			(width 0)
			(type default)
		)
	)
	(wire
		(pts
			(xy 191.77 93.98) (xy 191.77 91.44)
		)
		(stroke
			(width 0)
			(type default)
		)
	)
	(wire
		(pts
			(xy 220.98 275.59) (xy 220.98 273.05)
		)
		(stroke
			(width 0)
			(type default)
		)
	)
	(wire
		(pts
			(xy 389.89 91.44) (xy 389.89 102.87)
		)
		(stroke
			(width 0)
			(type default)
		)
	)
	(bus
		(pts
			(xy 58.42 165.1) (xy 58.42 167.64)
		)
		(stroke
			(width 0)
			(type default)
		)
	)
	(wire
		(pts
			(xy 78.74 264.16) (xy 78.74 266.7)
		)
		(stroke
			(width 0)
			(type default)
		)
	)
	(wire
		(pts
			(xy 81.28 205.74) (xy 66.04 205.74)
		)
		(stroke
			(width 0)
			(type default)
		)
	)
	(wire
		(pts
			(xy 290.83 195.58) (xy 307.34 195.58)
		)
		(stroke
			(width 0)
			(type default)
		)
	)
	(wire
		(pts
			(xy 80.01 231.14) (xy 80.01 232.41)
		)
		(stroke
			(width 0)
			(type default)
		)
	)
	(wire
		(pts
			(xy 85.09 67.31) (xy 85.09 66.04)
		)
		(stroke
			(width 0)
			(type default)
		)
	)
	(wire
		(pts
			(xy 81.28 227.33) (xy 67.31 227.33)
		)
		(stroke
			(width 0)
			(type default)
		)
	)
	(wire
		(pts
			(xy 83.82 45.72) (xy 100.33 45.72)
		)
		(stroke
			(width 0)
			(type default)
		)
	)
	(wire
		(pts
			(xy 119.38 269.24) (xy 119.38 274.32)
		)
		(stroke
			(width 0)
			(type default)
		)
	)
	(wire
		(pts
			(xy 341.63 93.98) (xy 341.63 96.52)
		)
		(stroke
			(width 0)
			(type default)
		)
	)
	(wire
		(pts
			(xy 176.53 260.35) (xy 173.99 260.35)
		)
		(stroke
			(width 0)
			(type default)
		)
	)
	(wire
		(pts
			(xy 365.76 125.73) (xy 365.76 128.27)
		)
		(stroke
			(width 0)
			(type default)
		)
	)
	(polyline
		(pts
			(xy 273.05 219.71) (xy 273.05 285.75)
		)
		(stroke
			(width 0)
			(type default)
		)
	)
	(wire
		(pts
			(xy 48.26 55.88) (xy 64.77 55.88)
		)
		(stroke
			(width 0)
			(type default)
		)
	)
	(bus
		(pts
			(xy 58.42 160.02) (xy 58.42 162.56)
		)
		(stroke
			(width 0)
			(type default)
		)
	)
	(wire
		(pts
			(xy 19.05 36.83) (xy 19.05 39.37)
		)
		(stroke
			(width 0)
			(type default)
		)
	)
	(wire
		(pts
			(xy 71.12 266.7) (xy 78.74 266.7)
		)
		(stroke
			(width 0)
			(type default)
		)
	)
	(wire
		(pts
			(xy 389.89 76.2) (xy 391.16 76.2)
		)
		(stroke
			(width 0)
			(type default)
		)
	)
	(wire
		(pts
			(xy 114.3 36.83) (xy 114.3 38.1)
		)
		(stroke
			(width 0)
			(type default)
		)
	)
	(wire
		(pts
			(xy 345.44 45.72) (xy 345.44 71.12)
		)
		(stroke
			(width 0)
			(type default)
		)
	)
	(wire
		(pts
			(xy 34.29 261.62) (xy 27.94 261.62)
		)
		(stroke
			(width 0)
			(type default)
		)
	)
	(wire
		(pts
			(xy 168.91 274.32) (xy 173.99 274.32)
		)
		(stroke
			(width 0)
			(type default)
		)
	)
	(wire
		(pts
			(xy 129.54 251.46) (xy 129.54 252.73)
		)
		(stroke
			(width 0)
			(type default)
		)
	)
	(wire
		(pts
			(xy 195.58 175.26) (xy 218.44 175.26)
		)
		(stroke
			(width 0)
			(type default)
		)
	)
	(wire
		(pts
			(xy 57.15 224.79) (xy 81.28 224.79)
		)
		(stroke
			(width 0)
			(type default)
		)
	)
	(polyline
		(pts
			(xy 12.7 245.11) (xy 185.42 245.11)
		)
		(stroke
			(width 0)
			(type default)
		)
	)
	(bus
		(pts
			(xy 303.53 68.58) (xy 303.53 71.12)
		)
		(stroke
			(width 0)
			(type default)
		)
	)
	(wire
		(pts
			(xy 201.93 224.79) (xy 201.93 226.06)
		)
		(stroke
			(width 0)
			(type default)
		)
	)
	(wire
		(pts
			(xy 44.45 180.34) (xy 44.45 189.23)
		)
		(stroke
			(width 0)
			(type default)
		)
	)
	(wire
		(pts
			(xy 78.74 266.7) (xy 78.74 269.24)
		)
		(stroke
			(width 0)
			(type default)
		)
	)
	(wire
		(pts
			(xy 300.99 104.14) (xy 303.53 104.14)
		)
		(stroke
			(width 0)
			(type default)
		)
	)
	(wire
		(pts
			(xy 336.55 45.72) (xy 336.55 73.66)
		)
		(stroke
			(width 0)
			(type default)
		)
	)
	(wire
		(pts
			(xy 68.58 158.75) (xy 81.28 158.75)
		)
		(stroke
			(width 0)
			(type default)
		)
	)
	(wire
		(pts
			(xy 78.74 269.24) (xy 78.74 271.78)
		)
		(stroke
			(width 0)
			(type default)
		)
	)
	(wire
		(pts
			(xy 148.59 82.55) (xy 191.77 82.55)
		)
		(stroke
			(width 0)
			(type default)
		)
	)
	(wire
		(pts
			(xy 48.26 45.72) (xy 64.77 45.72)
		)
		(stroke
			(width 0)
			(type default)
		)
	)
	(wire
		(pts
			(xy 320.04 40.64) (xy 320.04 39.37)
		)
		(stroke
			(width 0)
			(type default)
		)
	)
	(wire
		(pts
			(xy 201.93 215.9) (xy 218.44 215.9)
		)
		(stroke
			(width 0)
			(type default)
		)
	)
	(wire
		(pts
			(xy 48.26 78.74) (xy 55.88 78.74)
		)
		(stroke
			(width 0)
			(type default)
		)
	)
	(wire
		(pts
			(xy 200.66 198.12) (xy 218.44 198.12)
		)
		(stroke
			(width 0)
			(type default)
		)
	)
	(bus
		(pts
			(xy 45.72 41.91) (xy 45.72 43.18)
		)
		(stroke
			(width 0)
			(type default)
		)
	)
	(wire
		(pts
			(xy 320.04 31.75) (xy 320.04 34.29)
		)
		(stroke
			(width 0)
			(type default)
		)
	)
	(wire
		(pts
			(xy 195.58 187.96) (xy 218.44 187.96)
		)
		(stroke
			(width 0)
			(type default)
		)
	)
	(wire
		(pts
			(xy 83.82 58.42) (xy 100.33 58.42)
		)
		(stroke
			(width 0)
			(type default)
		)
	)
	(wire
		(pts
			(xy 243.84 215.9) (xy 250.19 215.9)
		)
		(stroke
			(width 0)
			(type default)
		)
	)
	(bus
		(pts
			(xy 35.56 190.5) (xy 35.56 193.04)
		)
		(stroke
			(width 0)
			(type default)
		)
	)
	(wire
		(pts
			(xy 78.74 261.62) (xy 78.74 264.16)
		)
		(stroke
			(width 0)
			(type default)
		)
	)
	(wire
		(pts
			(xy 339.09 162.56) (xy 340.36 162.56)
		)
		(stroke
			(width 0)
			(type default)
		)
	)
	(wire
		(pts
			(xy 129.54 260.35) (xy 137.16 260.35)
		)
		(stroke
			(width 0)
			(type default)
		)
	)
	(wire
		(pts
			(xy 358.14 162.56) (xy 359.41 162.56)
		)
		(stroke
			(width 0)
			(type default)
		)
	)
	(label "HDMI_OUT_CONN_D1_P"
		(at 195.58 172.72 0)
		(effects
			(font
				(size 1.27 1.27)
			)
			(justify left bottom)
		)
	)
	(label "VCCB"
		(at 90.17 106.68 0)
		(effects
			(font
				(size 1.27 1.27)
			)
			(justify left bottom)
		)
	)
	(label "HDMI_OUT_CONN_D2_N"
		(at 287.02 236.22 0)
		(effects
			(font
				(size 1.27 1.27)
			)
			(justify left bottom)
		)
	)
	(label "HDMI_IN.D2_N"
		(at 306.07 55.88 0)
		(effects
			(font
				(size 1.27 1.27)
			)
			(justify left bottom)
		)
	)
	(label "HDMI_OUT_CONN_D2_N"
		(at 133.35 175.26 180)
		(effects
			(font
				(size 1.27 1.27)
			)
			(justify right bottom)
		)
	)
	(label "HDMI_OUT_CONN_D2_P"
		(at 195.58 165.1 0)
		(effects
			(font
				(size 1.27 1.27)
			)
			(justify left bottom)
		)
	)
	(label "HDMI_CTL.SDA"
		(at 60.96 193.04 0)
		(effects
			(font
				(size 1.27 1.27)
			)
			(justify left bottom)
		)
	)
	(label "HDMI_IN_5V.SDA"
		(at 375.92 165.1 180)
		(effects
			(font
				(size 1.27 1.27)
			)
			(justify right bottom)
		)
	)
	(label "HDMI_IN_HPD_CONN"
		(at 358.14 203.2 0)
		(effects
			(font
				(size 1.27 1.27)
			)
			(justify left bottom)
		)
	)
	(label "SD_DAT0"
		(at 148.59 80.01 0)
		(effects
			(font
				(size 1.27 1.27)
			)
			(justify left bottom)
		)
	)
	(label "SD.CMD"
		(at 48.26 45.72 0)
		(effects
			(font
				(size 1.27 1.27)
			)
			(justify left bottom)
		)
	)
	(label "HDMI_OUT_C.SCL"
		(at 370.84 233.68 0)
		(effects
			(font
				(size 1.27 1.27)
			)
			(justify left bottom)
		)
	)
	(label "HDMI_CTL.SDA"
		(at 204.47 266.7 0)
		(effects
			(font
				(size 1.27 1.27)
			)
			(justify left bottom)
		)
	)
	(label "HDMI_CONN_5V"
		(at 370.84 238.76 0)
		(effects
			(font
				(size 1.27 1.27)
			)
			(justify left bottom)
		)
	)
	(label "HDMI_IN.D0_P"
		(at 306.07 66.04 0)
		(effects
			(font
				(size 1.27 1.27)
			)
			(justify left bottom)
		)
	)
	(label "~{HDMI_SEL}"
		(at 66.04 215.9 0)
		(effects
			(font
				(size 1.27 1.27)
			)
			(justify left bottom)
		)
	)
	(label "SD.CD"
		(at 48.26 78.74 0)
		(effects
			(font
				(size 1.27 1.27)
			)
			(justify left bottom)
		)
	)
	(label "HDMI_IN.D0_N"
		(at 306.07 71.12 0)
		(effects
			(font
				(size 1.27 1.27)
			)
			(justify left bottom)
		)
	)
	(label "HDMI_OUT_CONN_D1_N"
		(at 287.02 241.3 0)
		(effects
			(font
				(size 1.27 1.27)
			)
			(justify left bottom)
		)
	)
	(label "HDMI_OUT_CONN_D0_N"
		(at 195.58 182.88 0)
		(effects
			(font
				(size 1.27 1.27)
			)
			(justify left bottom)
		)
	)
	(label "HDMI_OUT_C.SDA"
		(at 133.35 186.69 180)
		(effects
			(font
				(size 1.27 1.27)
			)
			(justify right bottom)
		)
	)
	(label "HDMI0.HPD"
		(at 370.84 241.3 0)
		(effects
			(font
				(size 1.27 1.27)
			)
			(justify left bottom)
		)
	)
	(label "HDMI_OUT_CONN_CLK_P"
		(at 133.35 177.8 180)
		(effects
			(font
				(size 1.27 1.27)
			)
			(justify right bottom)
		)
	)
	(label "EQ_SEL"
		(at 46.99 269.24 0)
		(effects
			(font
				(size 1.27 1.27)
			)
			(justify left bottom)
		)
	)
	(label "HDMI_IN_5V.SCL"
		(at 375.92 167.64 180)
		(effects
			(font
				(size 1.27 1.27)
			)
			(justify right bottom)
		)
	)
	(label "~{HDMI_SEL}"
		(at 46.99 271.78 0)
		(effects
			(font
				(size 1.27 1.27)
			)
			(justify left bottom)
		)
	)
	(label "HDMI_IN_HPD_CONN"
		(at 370.84 96.52 0)
		(effects
			(font
				(size 1.27 1.27)
			)
			(justify left bottom)
		)
	)
	(label "HDMI_IN.D1_N"
		(at 306.07 63.5 0)
		(effects
			(font
				(size 1.27 1.27)
			)
			(justify left bottom)
		)
	)
	(label "HDMI0.HPD"
		(at 133.35 184.15 180)
		(effects
			(font
				(size 1.27 1.27)
			)
			(justify right bottom)
		)
	)
	(label "HDMI_CTL.SCL"
		(at 204.47 264.16 0)
		(effects
			(font
				(size 1.27 1.27)
			)
			(justify left bottom)
		)
	)
	(label "SD_DAT1"
		(at 100.33 55.88 180)
		(effects
			(font
				(size 1.27 1.27)
			)
			(justify right bottom)
		)
	)
	(label "HDMI_OUT_CONN_D2_P"
		(at 133.35 172.72 180)
		(effects
			(font
				(size 1.27 1.27)
			)
			(justify right bottom)
		)
	)
	(label "SD.DAT1"
		(at 48.26 55.88 0)
		(effects
			(font
				(size 1.27 1.27)
			)
			(justify left bottom)
		)
	)
	(label "HDMI_OUT_C.SCL"
		(at 200.66 195.58 0)
		(effects
			(font
				(size 1.27 1.27)
			)
			(justify left bottom)
		)
	)
	(label "SLEW_CTL"
		(at 66.04 220.98 0)
		(effects
			(font
				(size 1.27 1.27)
			)
			(justify left bottom)
		)
	)
	(label "HDMI_IN_5V.SDA"
		(at 370.84 86.36 0)
		(effects
			(font
				(size 1.27 1.27)
			)
			(justify left bottom)
		)
	)
	(label "SD_DAT0"
		(at 100.33 53.34 180)
		(effects
			(font
				(size 1.27 1.27)
			)
			(justify right bottom)
		)
	)
	(label "HDMI_IN.D2_P"
		(at 290.83 193.04 0)
		(effects
			(font
				(size 1.27 1.27)
			)
			(justify left bottom)
		)
	)
	(label "HDMI_IN_5V"
		(at 369.57 154.94 180)
		(effects
			(font
				(size 1.27 1.27)
			)
			(justify right bottom)
		)
	)
	(label "HDMI_IN.CLK_P"
		(at 306.07 73.66 0)
		(effects
			(font
				(size 1.27 1.27)
			)
			(justify left bottom)
		)
	)
	(label "SD.DAT3"
		(at 48.26 60.96 0)
		(effects
			(font
				(size 1.27 1.27)
			)
			(justify left bottom)
		)
	)
	(label "HDMI_OUT.D2_N"
		(at 60.96 175.26 0)
		(effects
			(font
				(size 1.27 1.27)
			)
			(justify left bottom)
		)
	)
	(label "HDMI_OUT_CONN_D0_P"
		(at 195.58 180.34 0)
		(effects
			(font
				(size 1.27 1.27)
			)
			(justify left bottom)
		)
	)
	(label "SD_DAT2"
		(at 148.59 69.85 0)
		(effects
			(font
				(size 1.27 1.27)
			)
			(justify left bottom)
		)
	)
	(label "HDMI_OUT_CONN_D1_P"
		(at 133.35 167.64 180)
		(effects
			(font
				(size 1.27 1.27)
			)
			(justify right bottom)
		)
	)
	(label "HDMI_IN_5V.SCL"
		(at 358.14 198.12 0)
		(effects
			(font
				(size 1.27 1.27)
			)
			(justify left bottom)
		)
	)
	(label "HDMI_IN.D0_N"
		(at 325.12 196.85 0)
		(effects
			(font
				(size 1.27 1.27)
			)
			(justify left bottom)
		)
	)
	(label "HDMI_IN_5V"
		(at 397.51 158.75 180)
		(effects
			(font
				(size 1.27 1.27)
			)
			(justify right bottom)
		)
	)
	(label "HDMI_OUT.D0_P"
		(at 60.96 162.56 0)
		(effects
			(font
				(size 1.27 1.27)
			)
			(justify left bottom)
		)
	)
	(label "SWAP{slash}POL"
		(at 66.04 205.74 0)
		(effects
			(font
				(size 1.27 1.27)
			)
			(justify left bottom)
		)
	)
	(label "SD.DAT0"
		(at 48.26 53.34 0)
		(effects
			(font
				(size 1.27 1.27)
			)
			(justify left bottom)
		)
	)
	(label "I2C_EN{slash}PIN"
		(at 66.04 208.28 0)
		(effects
			(font
				(size 1.27 1.27)
			)
			(justify left bottom)
		)
	)
	(label "HDMI_IN.D2_N"
		(at 290.83 195.58 0)
		(effects
			(font
				(size 1.27 1.27)
			)
			(justify left bottom)
		)
	)
	(label "HDMI_CTL.SCL"
		(at 60.96 195.58 0)
		(effects
			(font
				(size 1.27 1.27)
			)
			(justify left bottom)
		)
	)
	(label "SD.DAT2"
		(at 48.26 58.42 0)
		(effects
			(font
				(size 1.27 1.27)
			)
			(justify left bottom)
		)
	)
	(label "HDMI_OUT.D2_P"
		(at 60.96 172.72 0)
		(effects
			(font
				(size 1.27 1.27)
			)
			(justify left bottom)
		)
	)
	(label "VCCB"
		(at 119.38 106.68 180)
		(effects
			(font
				(size 1.27 1.27)
			)
			(justify right bottom)
		)
	)
	(label "SD_CLK"
		(at 100.33 48.26 180)
		(effects
			(font
				(size 1.27 1.27)
			)
			(justify right bottom)
		)
	)
	(label "HDMI_OUT.CLK_N"
		(at 60.96 180.34 0)
		(effects
			(font
				(size 1.27 1.27)
			)
			(justify left bottom)
		)
	)
	(label "HDMI_OUT_CONN_D0_N"
		(at 326.39 237.49 0)
		(effects
			(font
				(size 1.27 1.27)
			)
			(justify left bottom)
		)
	)
	(label "HDMI_IN.CLK_N"
		(at 306.07 78.74 0)
		(effects
			(font
				(size 1.27 1.27)
			)
			(justify left bottom)
		)
	)
	(label "HDMI_OUT_CONN_D0_N"
		(at 133.35 165.1 180)
		(effects
			(font
				(size 1.27 1.27)
			)
			(justify right bottom)
		)
	)
	(label "HDMI_OUT_CONN_CLK_N"
		(at 195.58 190.5 0)
		(effects
			(font
				(size 1.27 1.27)
			)
			(justify left bottom)
		)
	)
	(label "SD_CMD"
		(at 100.33 45.72 180)
		(effects
			(font
				(size 1.27 1.27)
			)
			(justify right bottom)
		)
	)
	(label "HDMI_5V"
		(at 173.99 215.9 0)
		(effects
			(font
				(size 1.27 1.27)
			)
			(justify left bottom)
		)
	)
	(label "HDMI_OUT.D1_N"
		(at 60.96 170.18 0)
		(effects
			(font
				(size 1.27 1.27)
			)
			(justify left bottom)
		)
	)
	(label "I2C_EN{slash}PIN"
		(at 46.99 264.16 0)
		(effects
			(font
				(size 1.27 1.27)
			)
			(justify left bottom)
		)
	)
	(label "HDMI_OUT_CONN_D2_N"
		(at 195.58 167.64 0)
		(effects
			(font
				(size 1.27 1.27)
			)
			(justify left bottom)
		)
	)
	(label "VCCB"
		(at 100.33 40.64 180)
		(effects
			(font
				(size 1.27 1.27)
			)
			(justify right bottom)
		)
	)
	(label "HDMI_VDD"
		(at 68.58 158.75 0)
		(effects
			(font
				(size 1.27 1.27)
			)
			(justify left bottom)
		)
	)
	(label "HDMI_IN.D0_P"
		(at 325.12 194.31 0)
		(effects
			(font
				(size 1.27 1.27)
			)
			(justify left bottom)
		)
	)
	(label "HDMI_OUT.CLK_P"
		(at 60.96 177.8 0)
		(effects
			(font
				(size 1.27 1.27)
			)
			(justify left bottom)
		)
	)
	(label "HDMI_IN_5V"
		(at 358.14 200.66 0)
		(effects
			(font
				(size 1.27 1.27)
			)
			(justify left bottom)
		)
	)
	(label "HDMI_OUT_C.SCL"
		(at 133.35 189.23 180)
		(effects
			(font
				(size 1.27 1.27)
			)
			(justify right bottom)
		)
	)
	(label "HDMI_OUT_I2C.SDA"
		(at 60.96 186.69 0)
		(effects
			(font
				(size 1.27 1.27)
			)
			(justify left bottom)
		)
	)
	(label "HDMI_IN.D1_N"
		(at 290.83 200.66 0)
		(effects
			(font
				(size 1.27 1.27)
			)
			(justify left bottom)
		)
	)
	(label "HDMI_OUT_CONN_D2_P"
		(at 287.02 233.68 0)
		(effects
			(font
				(size 1.27 1.27)
			)
			(justify left bottom)
		)
	)
	(label "HDMI_OUT_CONN_CLK_N"
		(at 326.39 242.57 0)
		(effects
			(font
				(size 1.27 1.27)
			)
			(justify left bottom)
		)
	)
	(label "HDMI0.HPD"
		(at 200.66 208.28 0)
		(effects
			(font
				(size 1.27 1.27)
			)
			(justify left bottom)
		)
	)
	(label "HDMI_IN_5V"
		(at 322.58 86.36 180)
		(effects
			(font
				(size 1.27 1.27)
			)
			(justify right bottom)
		)
	)
	(label "SD_DAT1"
		(at 148.59 82.55 0)
		(effects
			(font
				(size 1.27 1.27)
			)
			(justify left bottom)
		)
	)
	(label "SD.CD"
		(at 148.59 85.09 0)
		(effects
			(font
				(size 1.27 1.27)
			)
			(justify left bottom)
		)
	)
	(label "PRE_SEL"
		(at 46.99 266.7 0)
		(effects
			(font
				(size 1.27 1.27)
			)
			(justify left bottom)
		)
	)
	(label "HDMI_IN.D1_P"
		(at 306.07 58.42 0)
		(effects
			(font
				(size 1.27 1.27)
			)
			(justify left bottom)
		)
	)
	(label "SD.CLK"
		(at 48.26 48.26 0)
		(effects
			(font
				(size 1.27 1.27)
			)
			(justify left bottom)
		)
	)
	(label "SD_CMD"
		(at 148.59 74.93 0)
		(effects
			(font
				(size 1.27 1.27)
			)
			(justify left bottom)
		)
	)
	(label "HDMI_OUT_C.SDA"
		(at 370.84 236.22 0)
		(effects
			(font
				(size 1.27 1.27)
			)
			(justify left bottom)
		)
	)
	(label "HDMI_OUT_CONN_D0_P"
		(at 326.39 234.95 0)
		(effects
			(font
				(size 1.27 1.27)
			)
			(justify left bottom)
		)
	)
	(label "HDMI_IN_5V.SCL"
		(at 370.84 88.9 0)
		(effects
			(font
				(size 1.27 1.27)
			)
			(justify left bottom)
		)
	)
	(label "HDMI_OUT_CONN_CLK_P"
		(at 326.39 240.03 0)
		(effects
			(font
				(size 1.27 1.27)
			)
			(justify left bottom)
		)
	)
	(label "HDMI_OUT_CONN_CLK_N"
		(at 133.35 180.34 180)
		(effects
			(font
				(size 1.27 1.27)
			)
			(justify right bottom)
		)
	)
	(label "HDMI_OUT_CONN_CLK_P"
		(at 195.58 187.96 0)
		(effects
			(font
				(size 1.27 1.27)
			)
			(justify left bottom)
		)
	)
	(label "HDMI_OUT_CONN_D0_P"
		(at 133.35 162.56 180)
		(effects
			(font
				(size 1.27 1.27)
			)
			(justify right bottom)
		)
	)
	(label "HDMI_OUT_CONN_D1_N"
		(at 195.58 175.26 0)
		(effects
			(font
				(size 1.27 1.27)
			)
			(justify left bottom)
		)
	)
	(label "HDMI_IN.D1_P"
		(at 290.83 198.12 0)
		(effects
			(font
				(size 1.27 1.27)
			)
			(justify left bottom)
		)
	)
	(label "SD_DAT3"
		(at 100.33 60.96 180)
		(effects
			(font
				(size 1.27 1.27)
			)
			(justify right bottom)
		)
	)
	(label "HDMI_IN.CLK_P"
		(at 325.12 199.39 0)
		(effects
			(font
				(size 1.27 1.27)
			)
			(justify left bottom)
		)
	)
	(label "SD_DAT2"
		(at 100.33 58.42 180)
		(effects
			(font
				(size 1.27 1.27)
			)
			(justify right bottom)
		)
	)
	(label "SD_CLK"
		(at 148.59 77.47 0)
		(effects
			(font
				(size 1.27 1.27)
			)
			(justify left bottom)
		)
	)
	(label "PRE_SEL"
		(at 66.04 210.82 0)
		(effects
			(font
				(size 1.27 1.27)
			)
			(justify left bottom)
		)
	)
	(label "HDMI_OUT.D0_N"
		(at 60.96 165.1 0)
		(effects
			(font
				(size 1.27 1.27)
			)
			(justify left bottom)
		)
	)
	(label "HDMI_IN_5V"
		(at 370.84 93.98 0)
		(effects
			(font
				(size 1.27 1.27)
			)
			(justify left bottom)
		)
	)
	(label "HDMI_VDD"
		(at 165.1 260.35 0)
		(effects
			(font
				(size 1.27 1.27)
			)
			(justify left bottom)
		)
	)
	(label "HDMI_OUT_C.SDA"
		(at 200.66 198.12 0)
		(effects
			(font
				(size 1.27 1.27)
			)
			(justify left bottom)
		)
	)
	(label "HDMI_IN_I2C.SCL"
		(at 322.58 167.64 0)
		(effects
			(font
				(size 1.27 1.27)
			)
			(justify left bottom)
		)
	)
	(label "HDMI_OUT_CONN_D1_P"
		(at 287.02 238.76 0)
		(effects
			(font
				(size 1.27 1.27)
			)
			(justify left bottom)
		)
	)
	(label "EQ_SEL"
		(at 66.04 213.36 0)
		(effects
			(font
				(size 1.27 1.27)
			)
			(justify left bottom)
		)
	)
	(label "HDMI_IN_I2C.SDA"
		(at 322.58 165.1 0)
		(effects
			(font
				(size 1.27 1.27)
			)
			(justify left bottom)
		)
	)
	(label "HDMI_OUT_I2C.SCL"
		(at 60.96 189.23 0)
		(effects
			(font
				(size 1.27 1.27)
			)
			(justify left bottom)
		)
	)
	(label "TX_TERM_CTL"
		(at 46.99 274.32 0)
		(effects
			(font
				(size 1.27 1.27)
			)
			(justify left bottom)
		)
	)
	(label "HDMI_OUT.D1_P"
		(at 60.96 167.64 0)
		(effects
			(font
				(size 1.27 1.27)
			)
			(justify left bottom)
		)
	)
	(label "HDMI_OUT_CONN_D1_N"
		(at 133.35 170.18 180)
		(effects
			(font
				(size 1.27 1.27)
			)
			(justify right bottom)
		)
	)
	(label "HDMI_IN.CLK_N"
		(at 325.12 201.93 0)
		(effects
			(font
				(size 1.27 1.27)
			)
			(justify left bottom)
		)
	)
	(label "SLEW_CTL"
		(at 46.99 276.86 0)
		(effects
			(font
				(size 1.27 1.27)
			)
			(justify left bottom)
		)
	)
	(label "TX_TERM_CTL"
		(at 66.04 218.44 0)
		(effects
			(font
				(size 1.27 1.27)
			)
			(justify left bottom)
		)
	)
	(label "SD_DAT3"
		(at 148.59 72.39 0)
		(effects
			(font
				(size 1.27 1.27)
			)
			(justify left bottom)
		)
	)
	(label "HDMI_CONN_5V"
		(at 203.2 215.9 0)
		(effects
			(font
				(size 1.27 1.27)
			)
			(justify left bottom)
		)
	)
	(label "HDMI_CONN_5V"
		(at 157.48 176.53 180)
		(effects
			(font
				(size 1.27 1.27)
			)
			(justify right bottom)
		)
	)
	(label "HDMI_IN.D2_P"
		(at 306.07 50.8 0)
		(effects
			(font
				(size 1.27 1.27)
			)
			(justify left bottom)
		)
	)
	(label "SWAP{slash}POL"
		(at 46.99 261.62 0)
		(effects
			(font
				(size 1.27 1.27)
			)
			(justify left bottom)
		)
	)
	(label "HDMI_IN_5V.SDA"
		(at 358.14 195.58 0)
		(effects
			(font
				(size 1.27 1.27)
			)
			(justify left bottom)
		)
	)
	(label "VCCB"
		(at 109.22 36.83 0)
		(effects
			(font
				(size 1.27 1.27)
			)
			(justify left bottom)
		)
	)
	(global_label "SD_SEL"
		(shape input)
		(at 66.04 118.11 180)
		(fields_autoplaced yes)
		(effects
			(font
				(size 1.27 1.27)
			)
			(justify right)
		)
		(property "Intersheetrefs" "${INTERSHEET_REFS}"
			(at 56.2211 118.11 0)
			(effects
				(font
					(size 1.27 1.27)
				)
				(justify right)
			)
		)
	)
	(global_label "HDMI_OE"
		(shape input)
		(at 55.88 224.79 180)
		(fields_autoplaced yes)
		(effects
			(font
				(size 1.27 1.27)
			)
			(justify right)
		)
		(property "Intersheetrefs" "${INTERSHEET_REFS}"
			(at 45.4452 224.79 0)
			(effects
				(font
					(size 1.27 1.27)
				)
				(justify right)
			)
		)
	)
	(global_label "HDMI_OUT_HPD"
		(shape output)
		(at 76.2 182.88 180)
		(fields_autoplaced yes)
		(effects
			(font
				(size 1.27 1.27)
			)
			(justify right)
		)
		(property "Intersheetrefs" "${INTERSHEET_REFS}"
			(at 59.778 182.88 0)
			(effects
				(font
					(size 1.27 1.27)
				)
				(justify right)
			)
		)
	)
	(global_label "HDMI_IN_CD"
		(shape output)
		(at 295.91 116.84 180)
		(fields_autoplaced yes)
		(effects
			(font
				(size 1.27 1.27)
			)
			(justify right)
		)
		(property "Intersheetrefs" "${INTERSHEET_REFS}"
			(at 282.5118 116.84 0)
			(effects
				(font
					(size 1.27 1.27)
				)
				(justify right)
			)
		)
	)
	(global_label "HDMI_IN_HPD"
		(shape input)
		(at 297.18 104.14 180)
		(fields_autoplaced yes)
		(effects
			(font
				(size 1.27 1.27)
			)
			(justify right)
		)
		(property "Intersheetrefs" "${INTERSHEET_REFS}"
			(at 282.4513 104.14 0)
			(effects
				(font
					(size 1.27 1.27)
				)
				(justify right)
			)
		)
	)
	(hierarchical_label "HDMI_IN_I2C{I^{2}C}"
		(shape bidirectional)
		(at 317.5 160.02 180)
		(effects
			(font
				(size 1.27 1.27)
			)
			(justify right)
		)
	)
	(hierarchical_label "HDMI_OUT{TMDS}"
		(shape bidirectional)
		(at 54.61 157.48 180)
		(effects
			(font
				(size 1.27 1.27)
			)
			(justify right)
		)
	)
	(hierarchical_label "HDMI_CTL{I^{2}C}"
		(shape bidirectional)
		(at 33.02 187.96 180)
		(effects
			(font
				(size 1.27 1.27)
			)
			(justify right)
		)
	)
	(hierarchical_label "HDMI_IN{TMDS}"
		(shape bidirectional)
		(at 299.72 44.45 180)
		(effects
			(font
				(size 1.27 1.27)
			)
			(justify right)
		)
	)
	(hierarchical_label "HDMI_OUT_I2C{I^{2}C}"
		(shape bidirectional)
		(at 33.02 181.61 180)
		(effects
			(font
				(size 1.27 1.27)
			)
			(justify right)
		)
	)
	(hierarchical_label "SD{SDIO}"
		(shape bidirectional)
		(at 41.91 40.64 180)
		(effects
			(font
				(size 1.27 1.27)
			)
			(justify right)
		)
	)
	(symbol
		(lib_id "antmicroResistors0402:R_6k49_0402")
		(at 67.31 233.68 90)
		(unit 1)
		(exclude_from_sim no)
		(in_bom yes)
		(on_board yes)
		(dnp no)
		(property "Reference" "R76"
			(at 68.58 229.87 90)
			(effects
				(font
					(size 1.27 1.27)
					(thickness 0.15)
				)
				(justify right)
			)
		)
		(property "Value" "R_6k49_0402"
			(at 80.01 213.36 0)
			(effects
				(font
					(size 1.27 1.27)
					(thickness 0.15)
				)
				(justify left bottom)
				(hide yes)
			)
		)
		(property "Footprint" "antmicro-footprints:R_0402_1005Metric"
			(at 82.55 213.36 0)
			(effects
				(font
					(size 1.27 1.27)
					(thickness 0.15)
				)
				(justify left bottom)
				(hide yes)
			)
		)
		(property "Datasheet" "https://www.farnell.com/datasheets/3795017.pdf"
			(at 85.09 213.36 0)
			(effects
				(font
					(size 1.27 1.27)
					(thickness 0.15)
				)
				(justify left bottom)
				(hide yes)
			)
		)
		(property "Description" ""
			(at 67.31 233.68 0)
			(effects
				(font
					(size 1.27 1.27)
				)
				(hide yes)
			)
		)
		(property "MPN" "RMCF0402FT6K49"
			(at 87.63 213.36 0)
			(effects
				(font
					(size 1.27 1.27)
					(thickness 0.15)
				)
				(justify left bottom)
				(hide yes)
			)
		)
		(property "Manufacturer" "Stackpole Electronics"
			(at 90.17 213.36 0)
			(effects
				(font
					(size 1.27 1.27)
					(thickness 0.15)
				)
				(justify left bottom)
				(hide yes)
			)
		)
		(property "License" "Apache-2.0"
			(at 92.71 213.36 0)
			(effects
				(font
					(size 1.27 1.27)
					(thickness 0.15)
				)
				(justify left bottom)
				(hide yes)
			)
		)
		(property "Author" "Antmicro"
			(at 95.25 213.36 0)
			(effects
				(font
					(size 1.27 1.27)
					(thickness 0.15)
				)
				(justify left bottom)
				(hide yes)
			)
		)
		(property "Val" "6k49"
			(at 68.58 232.41 90)
			(effects
				(font
					(size 1.27 1.27)
					(thickness 0.15)
				)
				(justify right)
			)
		)
		(property "Tolerance" "1%"
			(at 77.47 213.36 0)
			(effects
				(font
					(size 1.27 1.27)
				)
				(justify left bottom)
				(hide yes)
			)
		)
		(pin "2"
		)
		(pin "1"
		)
		(instances
			(project "data-center-rdimm-ddr5-tester"
				(path ""
					(reference "R76")
					(unit 1)
				)
			)
		)
	)
	(symbol
		(lib_id "antmicroCapacitors0402:C_100n_0402")
		(at 21.59 114.3 90)
		(unit 1)
		(exclude_from_sim no)
		(in_bom yes)
		(on_board yes)
		(dnp no)
		(fields_autoplaced yes)
		(property "Reference" "C297"
			(at 25.4 110.4836 90)
			(effects
				(font
					(size 1.27 1.27)
					(thickness 0.15)
				)
				(justify right)
			)
		)
		(property "Value" "C_100n_0402"
			(at 31.75 93.98 0)
			(effects
				(font
					(size 1.27 1.27)
					(thickness 0.15)
				)
				(justify left bottom)
				(hide yes)
			)
		)
		(property "Footprint" "antmicro-footprints:C_0402_1005Metric"
			(at 34.29 93.98 0)
			(effects
				(font
					(size 1.27 1.27)
					(thickness 0.15)
				)
				(justify left bottom)
				(hide yes)
			)
		)
		(property "Datasheet" "https://www.murata.com/products/productdetail?partno=GRM155R61H104KE14%23"
			(at 36.83 93.98 0)
			(effects
				(font
					(size 1.27 1.27)
					(thickness 0.15)
				)
				(justify left bottom)
				(hide yes)
			)
		)
		(property "Description" ""
			(at 21.59 114.3 0)
			(effects
				(font
					(size 1.27 1.27)
				)
				(hide yes)
			)
		)
		(property "MPN" "GRM155R61H104KE14D"
			(at 39.37 93.98 0)
			(effects
				(font
					(size 1.27 1.27)
					(thickness 0.15)
				)
				(justify left bottom)
				(hide yes)
			)
		)
		(property "Manufacturer" "Murata"
			(at 41.91 93.98 0)
			(effects
				(font
					(size 1.27 1.27)
					(thickness 0.15)
				)
				(justify left bottom)
				(hide yes)
			)
		)
		(property "License" "Apache-2.0"
			(at 44.45 93.98 0)
			(effects
				(font
					(size 1.27 1.27)
					(thickness 0.15)
				)
				(justify left bottom)
				(hide yes)
			)
		)
		(property "Author" "Antmicro"
			(at 46.99 93.98 0)
			(effects
				(font
					(size 1.27 1.27)
					(thickness 0.15)
				)
				(justify left bottom)
				(hide yes)
			)
		)
		(property "Val" "100n"
			(at 25.4 113.0236 90)
			(effects
				(font
					(size 1.27 1.27)
					(thickness 0.15)
				)
				(justify right)
			)
		)
		(property "Voltage" "50V"
			(at 49.53 93.98 0)
			(effects
				(font
					(size 1.27 1.27)
				)
				(justify left bottom)
				(hide yes)
			)
		)
		(property "Dielectric" "X5R"
			(at 52.07 93.98 0)
			(effects
				(font
					(size 1.27 1.27)
				)
				(justify left bottom)
				(hide yes)
			)
		)
		(pin "1"
		)
		(pin "2"
		)
		(instances
			(project "data-center-rdimm-ddr5-tester"
				(path ""
					(reference "C297")
					(unit 1)
				)
			)
		)
	)
	(symbol
		(lib_id "antmicropower:GND")
		(at 163.83 101.6 0)
		(unit 1)
		(exclude_from_sim no)
		(in_bom yes)
		(on_board yes)
		(dnp no)
		(fields_autoplaced yes)
		(property "Reference" "#PWR0221"
			(at 163.83 107.95 0)
			(effects
				(font
					(size 1.27 1.27)
				)
				(hide yes)
			)
		)
		(property "Value" "GND"
			(at 161.925 106.045 0)
			(effects
				(font
					(size 1.27 1.27)
					(thickness 0.15)
				)
				(justify left bottom)
			)
		)
		(property "Footprint" ""
			(at 172.72 109.22 0)
			(effects
				(font
					(size 1.27 1.27)
					(thickness 0.15)
				)
				(justify left bottom)
				(hide yes)
			)
		)
		(property "Datasheet" ""
			(at 172.72 114.3 0)
			(effects
				(font
					(size 1.27 1.27)
					(thickness 0.15)
				)
				(justify left bottom)
				(hide yes)
			)
		)
		(property "Description" ""
			(at 163.83 101.6 0)
			(effects
				(font
					(size 1.27 1.27)
				)
				(hide yes)
			)
		)
		(property "Author" "Antmicro"
			(at 172.72 106.68 0)
			(effects
				(font
					(size 1.27 1.27)
					(thickness 0.15)
				)
				(justify left bottom)
				(hide yes)
			)
		)
		(property "License" "Apache-2.0"
			(at 172.72 109.22 0)
			(effects
				(font
					(size 1.27 1.27)
					(thickness 0.15)
				)
				(justify left bottom)
				(hide yes)
			)
		)
		(pin "1"
		)
		(instances
			(project "data-center-rdimm-ddr5-tester"
				(path ""
					(reference "#PWR0221")
					(unit 1)
				)
			)
		)
	)
	(symbol
		(lib_id "antmicropower:GND")
		(at 320.04 40.64 0)
		(mirror y)
		(unit 1)
		(exclude_from_sim no)
		(in_bom yes)
		(on_board yes)
		(dnp no)
		(fields_autoplaced yes)
		(property "Reference" "#PWR0265"
			(at 320.04 46.99 0)
			(effects
				(font
					(size 1.27 1.27)
				)
				(hide yes)
			)
		)
		(property "Value" "GND"
			(at 321.945 45.085 0)
			(effects
				(font
					(size 1.27 1.27)
					(thickness 0.15)
				)
				(justify left bottom)
			)
		)
		(property "Footprint" ""
			(at 311.15 48.26 0)
			(effects
				(font
					(size 1.27 1.27)
					(thickness 0.15)
				)
				(justify left bottom)
				(hide yes)
			)
		)
		(property "Datasheet" ""
			(at 311.15 53.34 0)
			(effects
				(font
					(size 1.27 1.27)
					(thickness 0.15)
				)
				(justify left bottom)
				(hide yes)
			)
		)
		(property "Description" ""
			(at 320.04 40.64 0)
			(effects
				(font
					(size 1.27 1.27)
				)
				(hide yes)
			)
		)
		(property "Author" "Antmicro"
			(at 311.15 45.72 0)
			(effects
				(font
					(size 1.27 1.27)
					(thickness 0.15)
				)
				(justify left bottom)
				(hide yes)
			)
		)
		(property "License" "Apache-2.0"
			(at 311.15 48.26 0)
			(effects
				(font
					(size 1.27 1.27)
					(thickness 0.15)
				)
				(justify left bottom)
				(hide yes)
			)
		)
		(pin "1"
		)
		(instances
			(project "data-center-rdimm-ddr5-tester"
				(path ""
					(reference "#PWR0265")
					(unit 1)
				)
			)
		)
	)
	(symbol
		(lib_id "antmicropower:GND")
		(at 238.76 276.86 0)
		(unit 1)
		(exclude_from_sim no)
		(in_bom yes)
		(on_board yes)
		(dnp no)
		(property "Reference" "#PWR0151"
			(at 247.65 279.4 0)
			(effects
				(font
					(size 1.27 1.27)
					(thickness 0.15)
				)
				(justify left bottom)
				(hide yes)
			)
		)
		(property "Value" "GND"
			(at 238.76 280.67 0)
			(effects
				(font
					(size 1.27 1.27)
					(thickness 0.15)
				)
			)
		)
		(property "Footprint" ""
			(at 247.65 284.48 0)
			(effects
				(font
					(size 1.27 1.27)
					(thickness 0.15)
				)
				(justify left bottom)
				(hide yes)
			)
		)
		(property "Datasheet" ""
			(at 247.65 289.56 0)
			(effects
				(font
					(size 1.27 1.27)
					(thickness 0.15)
				)
				(justify left bottom)
				(hide yes)
			)
		)
		(property "Description" ""
			(at 238.76 276.86 0)
			(effects
				(font
					(size 1.27 1.27)
				)
				(hide yes)
			)
		)
		(property "Author" "Antmicro"
			(at 247.65 284.48 0)
			(effects
				(font
					(size 1.27 1.27)
					(thickness 0.15)
				)
				(justify left bottom)
				(hide yes)
			)
		)
		(property "License" "Apache-2.0"
			(at 247.65 287.02 0)
			(effects
				(font
					(size 1.27 1.27)
					(thickness 0.15)
				)
				(justify left bottom)
				(hide yes)
			)
		)
		(pin "1"
		)
		(instances
			(project "data-center-rdimm-ddr5-tester"
				(path ""
					(reference "#PWR0151")
					(unit 1)
				)
			)
		)
	)
	(symbol
		(lib_id "antmicroResistors0402:R_1k_0402")
		(at 349.25 93.98 0)
		(unit 1)
		(exclude_from_sim no)
		(in_bom yes)
		(on_board yes)
		(dnp no)
		(fields_autoplaced yes)
		(property "Reference" "R81"
			(at 351.79 87.63 0)
			(effects
				(font
					(size 1.27 1.27)
					(thickness 0.15)
				)
			)
		)
		(property "Value" "R_1k_0402"
			(at 369.57 106.68 0)
			(effects
				(font
					(size 1.27 1.27)
					(thickness 0.15)
				)
				(justify left bottom)
				(hide yes)
			)
		)
		(property "Footprint" "antmicro-footprints:R_0402_1005Metric"
			(at 369.57 109.22 0)
			(effects
				(font
					(size 1.27 1.27)
					(thickness 0.15)
				)
				(justify left bottom)
				(hide yes)
			)
		)
		(property "Datasheet" "https://www.bourns.com/docs/product-datasheets/cr.pdf"
			(at 369.57 111.76 0)
			(effects
				(font
					(size 1.27 1.27)
					(thickness 0.15)
				)
				(justify left bottom)
				(hide yes)
			)
		)
		(property "Description" ""
			(at 349.25 93.98 0)
			(effects
				(font
					(size 1.27 1.27)
				)
				(hide yes)
			)
		)
		(property "MPN" "CR0402-FX-1001GLF"
			(at 369.57 114.3 0)
			(effects
				(font
					(size 1.27 1.27)
					(thickness 0.15)
				)
				(justify left bottom)
				(hide yes)
			)
		)
		(property "Manufacturer" "Bourns"
			(at 369.57 116.84 0)
			(effects
				(font
					(size 1.27 1.27)
					(thickness 0.15)
				)
				(justify left bottom)
				(hide yes)
			)
		)
		(property "License" "Apache-2.0"
			(at 369.57 119.38 0)
			(effects
				(font
					(size 1.27 1.27)
					(thickness 0.15)
				)
				(justify left bottom)
				(hide yes)
			)
		)
		(property "Author" "Antmicro"
			(at 369.57 121.92 0)
			(effects
				(font
					(size 1.27 1.27)
					(thickness 0.15)
				)
				(justify left bottom)
				(hide yes)
			)
		)
		(property "Val" "1k"
			(at 351.79 90.17 0)
			(effects
				(font
					(size 1.27 1.27)
					(thickness 0.15)
				)
			)
		)
		(property "Tolerance" "1%"
			(at 369.57 104.14 0)
			(effects
				(font
					(size 1.27 1.27)
				)
				(justify left bottom)
				(hide yes)
			)
		)
		(pin "2"
		)
		(pin "1"
		)
		(instances
			(project "data-center-rdimm-ddr5-tester"
				(path ""
					(reference "R81")
					(unit 1)
				)
			)
		)
	)
	(symbol
		(lib_id "antmicropower:GND")
		(at 288.29 166.37 0)
		(mirror y)
		(unit 1)
		(exclude_from_sim no)
		(in_bom yes)
		(on_board yes)
		(dnp no)
		(property "Reference" "#PWR0502"
			(at 288.29 172.72 0)
			(effects
				(font
					(size 1.27 1.27)
				)
				(hide yes)
			)
		)
		(property "Value" "GND"
			(at 288.29 170.18 0)
			(effects
				(font
					(size 1.27 1.27)
					(thickness 0.15)
				)
			)
		)
		(property "Footprint" ""
			(at 279.4 173.99 0)
			(effects
				(font
					(size 1.27 1.27)
					(thickness 0.15)
				)
				(justify left bottom)
				(hide yes)
			)
		)
		(property "Datasheet" ""
			(at 279.4 179.07 0)
			(effects
				(font
					(size 1.27 1.27)
					(thickness 0.15)
				)
				(justify left bottom)
				(hide yes)
			)
		)
		(property "Description" ""
			(at 288.29 166.37 0)
			(effects
				(font
					(size 1.27 1.27)
				)
				(hide yes)
			)
		)
		(property "Author" "Antmicro"
			(at 279.4 171.45 0)
			(effects
				(font
					(size 1.27 1.27)
					(thickness 0.15)
				)
				(justify left bottom)
				(hide yes)
			)
		)
		(property "License" "Apache-2.0"
			(at 279.4 173.99 0)
			(effects
				(font
					(size 1.27 1.27)
					(thickness 0.15)
				)
				(justify left bottom)
				(hide yes)
			)
		)
		(pin "1"
		)
		(instances
			(project "data-center-rdimm-ddr5-tester"
				(path ""
					(reference "#PWR0502")
					(unit 1)
				)
			)
		)
	)
	(symbol
		(lib_id "antmicropower:GND")
		(at 191.77 93.98 0)
		(unit 1)
		(exclude_from_sim no)
		(in_bom yes)
		(on_board yes)
		(dnp no)
		(fields_autoplaced yes)
		(property "Reference" "#PWR0224"
			(at 191.77 100.33 0)
			(effects
				(font
					(size 1.27 1.27)
				)
				(hide yes)
			)
		)
		(property "Value" "GND"
			(at 189.865 98.425 0)
			(effects
				(font
					(size 1.27 1.27)
					(thickness 0.15)
				)
				(justify left bottom)
			)
		)
		(property "Footprint" ""
			(at 200.66 101.6 0)
			(effects
				(font
					(size 1.27 1.27)
					(thickness 0.15)
				)
				(justify left bottom)
				(hide yes)
			)
		)
		(property "Datasheet" ""
			(at 200.66 106.68 0)
			(effects
				(font
					(size 1.27 1.27)
					(thickness 0.15)
				)
				(justify left bottom)
				(hide yes)
			)
		)
		(property "Description" ""
			(at 191.77 93.98 0)
			(effects
				(font
					(size 1.27 1.27)
				)
				(hide yes)
			)
		)
		(property "Author" "Antmicro"
			(at 200.66 99.06 0)
			(effects
				(font
					(size 1.27 1.27)
					(thickness 0.15)
				)
				(justify left bottom)
				(hide yes)
			)
		)
		(property "License" "Apache-2.0"
			(at 200.66 101.6 0)
			(effects
				(font
					(size 1.27 1.27)
					(thickness 0.15)
				)
				(justify left bottom)
				(hide yes)
			)
		)
		(pin "1"
		)
		(instances
			(project "data-center-rdimm-ddr5-tester"
				(path ""
					(reference "#PWR0224")
					(unit 1)
				)
			)
		)
	)
	(symbol
		(lib_id "antmicroTVSDiodes:TPD4E05U06QDQARQ1")
		(at 350.52 234.95 0)
		(unit 1)
		(exclude_from_sim no)
		(in_bom yes)
		(on_board yes)
		(dnp no)
		(property "Reference" "U11"
			(at 354.33 227.33 0)
			(effects
				(font
					(size 1.27 1.27)
				)
				(justify left)
			)
		)
		(property "Value" "TPD4E05U06QDQARQ1"
			(at 352.425 248.285 0)
			(effects
				(font
					(size 1.27 1.27)
					(thickness 0.15)
				)
				(justify left)
				(hide yes)
			)
		)
		(property "Footprint" "antmicro-footprints:USON-10_2.5x1mm_P0.5mm"
			(at 374.65 240.03 0)
			(effects
				(font
					(size 1.27 1.27)
					(thickness 0.15)
				)
				(justify left bottom)
				(hide yes)
			)
		)
		(property "Datasheet" "https://www.ti.com/lit/ds/symlink/tpd4e05u06-q1.pdf?HQS=dis-mous-null-mousermode-dsf-pf-null-wwe&ts=1663591265741&ref_url=https%253A%252F%252Fwww.mouser.com%252F"
			(at 374.65 242.57 0)
			(effects
				(font
					(size 1.27 1.27)
					(thickness 0.15)
				)
				(justify left bottom)
				(hide yes)
			)
		)
		(property "Description" ""
			(at 350.52 234.95 0)
			(effects
				(font
					(size 1.27 1.27)
				)
				(hide yes)
			)
		)
		(property "Manufacturer" "Texas Instruments"
			(at 374.65 245.11 0)
			(effects
				(font
					(size 1.27 1.27)
					(thickness 0.15)
				)
				(justify left bottom)
				(hide yes)
			)
		)
		(property "MPN" "TPD4E05U06QDQARQ1"
			(at 346.075 230.505 0)
			(effects
				(font
					(size 1.27 1.27)
					(thickness 0.15)
				)
				(justify left)
			)
		)
		(property "Author" "Antmicro"
			(at 374.65 250.19 0)
			(effects
				(font
					(size 1.27 1.27)
					(thickness 0.15)
				)
				(justify left bottom)
				(hide yes)
			)
		)
		(property "License" "Apache-2.0"
			(at 374.65 252.73 0)
			(effects
				(font
					(size 1.27 1.27)
					(thickness 0.15)
				)
				(justify left bottom)
				(hide yes)
			)
		)
		(pin "1"
		)
		(pin "10"
		)
		(pin "2"
		)
		(pin "3"
		)
		(pin "4"
		)
		(pin "5"
		)
		(pin "6"
		)
		(pin "7"
		)
		(pin "8"
		)
		(pin "9"
		)
		(instances
			(project "data-center-rdimm-ddr5-tester"
				(path ""
					(reference "U11")
					(unit 1)
				)
			)
		)
	)
	(symbol
		(lib_id "antmicropower:+3V3")
		(at 339.09 157.48 0)
		(unit 1)
		(exclude_from_sim no)
		(in_bom yes)
		(on_board yes)
		(dnp no)
		(fields_autoplaced yes)
		(property "Reference" "#PWR0228"
			(at 354.33 157.48 0)
			(effects
				(font
					(size 1.27 1.27)
					(thickness 0.15)
				)
				(justify left bottom)
				(hide yes)
			)
		)
		(property "Value" "+3V3"
			(at 339.09 152.4 0)
			(effects
				(font
					(size 1.27 1.27)
					(thickness 0.15)
				)
			)
		)
		(property "Footprint" ""
			(at 354.33 165.1 0)
			(effects
				(font
					(size 1.27 1.27)
					(thickness 0.15)
				)
				(justify left bottom)
				(hide yes)
			)
		)
		(property "Datasheet" ""
			(at 354.33 167.64 0)
			(effects
				(font
					(size 1.27 1.27)
					(thickness 0.15)
				)
				(justify left bottom)
				(hide yes)
			)
		)
		(property "Description" ""
			(at 339.09 157.48 0)
			(effects
				(font
					(size 1.27 1.27)
				)
				(hide yes)
			)
		)
		(property "Author" "Antmicro"
			(at 354.33 160.02 0)
			(effects
				(font
					(size 1.27 1.27)
					(thickness 0.15)
				)
				(justify left bottom)
				(hide yes)
			)
		)
		(property "License" "Apache-2.0"
			(at 354.33 162.56 0)
			(effects
				(font
					(size 1.27 1.27)
					(thickness 0.15)
				)
				(justify left bottom)
				(hide yes)
			)
		)
		(pin "1"
		)
		(instances
			(project "data-center-rdimm-ddr5-tester"
				(path ""
					(reference "#PWR0228")
					(unit 1)
				)
			)
		)
	)
	(symbol
		(lib_id "antmicroVideoConnectors:HDMI-A_WE_685119134923")
		(at 218.44 165.1 0)
		(unit 1)
		(exclude_from_sim no)
		(in_bom yes)
		(on_board yes)
		(dnp no)
		(fields_autoplaced yes)
		(property "Reference" "J4"
			(at 231.14 157.48 0)
			(effects
				(font
					(size 1.27 1.27)
					(thickness 0.15)
				)
			)
		)
		(property "Value" "HDMI-A_WE_685119134923"
			(at 231.14 161.3987 0)
			(effects
				(font
					(size 1.27 1.27)
					(thickness 0.15)
				)
				(hide yes)
			)
		)
		(property "Footprint" "antmicro-footprints:HDMI-A_Receptacle_WE_685119134923"
			(at 254 172.72 0)
			(effects
				(font
					(size 1.27 1.27)
					(thickness 0.15)
				)
				(justify left bottom)
				(hide yes)
			)
		)
		(property "Datasheet" "https://www.we-online.com/components/products/datasheet/685119134923.pdf"
			(at 254 175.26 0)
			(effects
				(font
					(size 1.27 1.27)
					(thickness 0.15)
				)
				(justify left bottom)
				(hide yes)
			)
		)
		(property "Description" ""
			(at 218.44 165.1 0)
			(effects
				(font
					(size 1.27 1.27)
				)
				(hide yes)
			)
		)
		(property "MPN" "685119134923"
			(at 231.14 160.02 0)
			(effects
				(font
					(size 1.27 1.27)
					(thickness 0.15)
				)
			)
		)
		(property "Manufacturer" "Würth Elektronik"
			(at 254 180.34 0)
			(effects
				(font
					(size 1.27 1.27)
					(thickness 0.15)
				)
				(justify left bottom)
				(hide yes)
			)
		)
		(property "Author" "Antmicro"
			(at 254 182.88 0)
			(effects
				(font
					(size 1.27 1.27)
					(thickness 0.15)
				)
				(justify left bottom)
				(hide yes)
			)
		)
		(property "License" "Apache-2.0"
			(at 254 185.42 0)
			(effects
				(font
					(size 1.27 1.27)
					(thickness 0.15)
				)
				(justify left bottom)
				(hide yes)
			)
		)
		(pin "1"
		)
		(pin "10"
		)
		(pin "11"
		)
		(pin "12"
		)
		(pin "13"
		)
		(pin "14"
		)
		(pin "15"
		)
		(pin "16"
		)
		(pin "17"
		)
		(pin "18"
		)
		(pin "19"
		)
		(pin "2"
		)
		(pin "3"
		)
		(pin "4"
		)
		(pin "5"
		)
		(pin "6"
		)
		(pin "7"
		)
		(pin "8"
		)
		(pin "9"
		)
		(pin "SH"
		)
		(instances
			(project "data-center-rdimm-ddr5-tester"
				(path ""
					(reference "J4")
					(unit 1)
				)
			)
		)
	)
	(symbol
		(lib_id "antmicropower:GND")
		(at 114.3 116.84 0)
		(unit 1)
		(exclude_from_sim no)
		(in_bom yes)
		(on_board yes)
		(dnp no)
		(fields_autoplaced yes)
		(property "Reference" "#PWR0479"
			(at 114.3 123.19 0)
			(effects
				(font
					(size 1.27 1.27)
				)
				(hide yes)
			)
		)
		(property "Value" "GND"
			(at 112.395 121.285 0)
			(effects
				(font
					(size 1.27 1.27)
					(thickness 0.15)
				)
				(justify left bottom)
			)
		)
		(property "Footprint" ""
			(at 123.19 124.46 0)
			(effects
				(font
					(size 1.27 1.27)
					(thickness 0.15)
				)
				(justify left bottom)
				(hide yes)
			)
		)
		(property "Datasheet" ""
			(at 123.19 129.54 0)
			(effects
				(font
					(size 1.27 1.27)
					(thickness 0.15)
				)
				(justify left bottom)
				(hide yes)
			)
		)
		(property "Description" ""
			(at 114.3 116.84 0)
			(effects
				(font
					(size 1.27 1.27)
				)
				(hide yes)
			)
		)
		(property "Author" "Antmicro"
			(at 123.19 121.92 0)
			(effects
				(font
					(size 1.27 1.27)
					(thickness 0.15)
				)
				(justify left bottom)
				(hide yes)
			)
		)
		(property "License" "Apache-2.0"
			(at 123.19 124.46 0)
			(effects
				(font
					(size 1.27 1.27)
					(thickness 0.15)
				)
				(justify left bottom)
				(hide yes)
			)
		)
		(pin "1"
		)
		(instances
			(project "data-center-rdimm-ddr5-tester"
				(path ""
					(reference "#PWR0479")
					(unit 1)
				)
			)
		)
	)
	(symbol
		(lib_id "antmicropower:GND")
		(at 19.05 45.72 0)
		(unit 1)
		(exclude_from_sim no)
		(in_bom yes)
		(on_board yes)
		(dnp no)
		(fields_autoplaced yes)
		(property "Reference" "#PWR0480"
			(at 27.94 48.26 0)
			(effects
				(font
					(size 1.27 1.27)
					(thickness 0.15)
				)
				(justify left bottom)
				(hide yes)
			)
		)
		(property "Value" "GND"
			(at 19.05 50.165 0)
			(effects
				(font
					(size 1.27 1.27)
					(thickness 0.15)
				)
			)
		)
		(property "Footprint" ""
			(at 27.94 53.34 0)
			(effects
				(font
					(size 1.27 1.27)
					(thickness 0.15)
				)
				(justify left bottom)
				(hide yes)
			)
		)
		(property "Datasheet" ""
			(at 27.94 58.42 0)
			(effects
				(font
					(size 1.27 1.27)
					(thickness 0.15)
				)
				(justify left bottom)
				(hide yes)
			)
		)
		(property "Description" ""
			(at 19.05 45.72 0)
			(effects
				(font
					(size 1.27 1.27)
				)
				(hide yes)
			)
		)
		(property "Author" "Antmicro"
			(at 27.94 53.34 0)
			(effects
				(font
					(size 1.27 1.27)
					(thickness 0.15)
				)
				(justify left bottom)
				(hide yes)
			)
		)
		(property "License" "Apache-2.0"
			(at 27.94 55.88 0)
			(effects
				(font
					(size 1.27 1.27)
					(thickness 0.15)
				)
				(justify left bottom)
				(hide yes)
			)
		)
		(pin "1"
		)
		(instances
			(project "data-center-rdimm-ddr5-tester"
				(path ""
					(reference "#PWR0480")
					(unit 1)
				)
			)
		)
	)
	(symbol
		(lib_id "antmicropower:+3V3")
		(at 29.21 161.29 0)
		(mirror y)
		(unit 1)
		(exclude_from_sim no)
		(in_bom yes)
		(on_board yes)
		(dnp no)
		(fields_autoplaced yes)
		(property "Reference" "#PWR0532"
			(at 13.97 161.29 0)
			(effects
				(font
					(size 1.27 1.27)
					(thickness 0.15)
				)
				(justify left bottom)
				(hide yes)
			)
		)
		(property "Value" "+3V3"
			(at 29.21 156.21 0)
			(effects
				(font
					(size 1.27 1.27)
					(thickness 0.15)
				)
			)
		)
		(property "Footprint" ""
			(at 13.97 168.91 0)
			(effects
				(font
					(size 1.27 1.27)
					(thickness 0.15)
				)
				(justify left bottom)
				(hide yes)
			)
		)
		(property "Datasheet" ""
			(at 13.97 171.45 0)
			(effects
				(font
					(size 1.27 1.27)
					(thickness 0.15)
				)
				(justify left bottom)
				(hide yes)
			)
		)
		(property "Description" ""
			(at 29.21 161.29 0)
			(effects
				(font
					(size 1.27 1.27)
				)
				(hide yes)
			)
		)
		(property "Author" "Antmicro"
			(at 13.97 163.83 0)
			(effects
				(font
					(size 1.27 1.27)
					(thickness 0.15)
				)
				(justify left bottom)
				(hide yes)
			)
		)
		(property "License" "Apache-2.0"
			(at 13.97 166.37 0)
			(effects
				(font
					(size 1.27 1.27)
					(thickness 0.15)
				)
				(justify left bottom)
				(hide yes)
			)
		)
		(pin "1"
		)
		(instances
			(project "data-center-rdimm-ddr5-tester"
				(path ""
					(reference "#PWR0532")
					(unit 1)
				)
			)
		)
	)
	(symbol
		(lib_id "antmicropower:GND")
		(at 34.29 115.57 0)
		(unit 1)
		(exclude_from_sim no)
		(in_bom yes)
		(on_board yes)
		(dnp no)
		(fields_autoplaced yes)
		(property "Reference" "#PWR0477"
			(at 43.18 118.11 0)
			(effects
				(font
					(size 1.27 1.27)
					(thickness 0.15)
				)
				(justify left bottom)
				(hide yes)
			)
		)
		(property "Value" "GND"
			(at 34.29 120.015 0)
			(effects
				(font
					(size 1.27 1.27)
					(thickness 0.15)
				)
			)
		)
		(property "Footprint" ""
			(at 43.18 123.19 0)
			(effects
				(font
					(size 1.27 1.27)
					(thickness 0.15)
				)
				(justify left bottom)
				(hide yes)
			)
		)
		(property "Datasheet" ""
			(at 43.18 128.27 0)
			(effects
				(font
					(size 1.27 1.27)
					(thickness 0.15)
				)
				(justify left bottom)
				(hide yes)
			)
		)
		(property "Description" ""
			(at 34.29 115.57 0)
			(effects
				(font
					(size 1.27 1.27)
				)
				(hide yes)
			)
		)
		(property "Author" "Antmicro"
			(at 43.18 123.19 0)
			(effects
				(font
					(size 1.27 1.27)
					(thickness 0.15)
				)
				(justify left bottom)
				(hide yes)
			)
		)
		(property "License" "Apache-2.0"
			(at 43.18 125.73 0)
			(effects
				(font
					(size 1.27 1.27)
					(thickness 0.15)
				)
				(justify left bottom)
				(hide yes)
			)
		)
		(pin "1"
		)
		(instances
			(project "data-center-rdimm-ddr5-tester"
				(path ""
					(reference "#PWR0477")
					(unit 1)
				)
			)
		)
	)
	(symbol
		(lib_id "antmicroTVSDiodes:TPD4E05U06QDQARQ1")
		(at 307.34 193.04 0)
		(unit 1)
		(exclude_from_sim no)
		(in_bom yes)
		(on_board yes)
		(dnp no)
		(property "Reference" "U37"
			(at 309.88 189.23 0)
			(effects
				(font
					(size 1.27 1.27)
				)
				(justify left)
			)
		)
		(property "Value" "TPD4E05U06QDQARQ1"
			(at 309.88 206.375 0)
			(effects
				(font
					(size 1.27 1.27)
					(thickness 0.15)
				)
				(justify left)
				(hide yes)
			)
		)
		(property "Footprint" "antmicro-footprints:USON-10_2.5x1mm_P0.5mm"
			(at 331.47 198.12 0)
			(effects
				(font
					(size 1.27 1.27)
					(thickness 0.15)
				)
				(justify left bottom)
				(hide yes)
			)
		)
		(property "Datasheet" "https://www.ti.com/lit/ds/symlink/tpd4e05u06-q1.pdf?HQS=dis-mous-null-mousermode-dsf-pf-null-wwe&ts=1663591265741&ref_url=https%253A%252F%252Fwww.mouser.com%252F"
			(at 331.47 200.66 0)
			(effects
				(font
					(size 1.27 1.27)
					(thickness 0.15)
				)
				(justify left bottom)
				(hide yes)
			)
		)
		(property "Description" ""
			(at 307.34 193.04 0)
			(effects
				(font
					(size 1.27 1.27)
				)
				(hide yes)
			)
		)
		(property "Manufacturer" "Texas Instruments"
			(at 331.47 203.2 0)
			(effects
				(font
					(size 1.27 1.27)
					(thickness 0.15)
				)
				(justify left bottom)
				(hide yes)
			)
		)
		(property "MPN" "TPD4E05U06QDQARQ1"
			(at 306.705 206.375 0)
			(effects
				(font
					(size 1.27 1.27)
					(thickness 0.15)
				)
				(justify left)
			)
		)
		(property "Author" "Antmicro"
			(at 331.47 208.28 0)
			(effects
				(font
					(size 1.27 1.27)
					(thickness 0.15)
				)
				(justify left bottom)
				(hide yes)
			)
		)
		(property "License" "Apache-2.0"
			(at 331.47 210.82 0)
			(effects
				(font
					(size 1.27 1.27)
					(thickness 0.15)
				)
				(justify left bottom)
				(hide yes)
			)
		)
		(pin "1"
		)
		(pin "10"
		)
		(pin "2"
		)
		(pin "3"
		)
		(pin "4"
		)
		(pin "5"
		)
		(pin "6"
		)
		(pin "7"
		)
		(pin "8"
		)
		(pin "9"
		)
		(instances
			(project "data-center-rdimm-ddr5-tester"
				(path ""
					(reference "U37")
					(unit 1)
				)
			)
		)
	)
	(symbol
		(lib_id "antmicroCapacitors0402:C_10u_6.3V_0402")
		(at 320.04 39.37 90)
		(unit 1)
		(exclude_from_sim no)
		(in_bom yes)
		(on_board yes)
		(dnp no)
		(fields_autoplaced yes)
		(property "Reference" "C301"
			(at 322.3641 35.993 90)
			(effects
				(font
					(size 1.27 1.27)
					(thickness 0.15)
				)
				(justify right)
			)
		)
		(property "Value" "C_10u_6.3V_0402"
			(at 330.2 19.05 0)
			(effects
				(font
					(size 1.27 1.27)
					(thickness 0.15)
				)
				(justify left bottom)
				(hide yes)
			)
		)
		(property "Footprint" "antmicro-footprints:C_0402_1005Metric"
			(at 332.74 19.05 0)
			(effects
				(font
					(size 1.27 1.27)
					(thickness 0.15)
				)
				(justify left bottom)
				(hide yes)
			)
		)
		(property "Datasheet" "https://www.murata.com/products/productdetail?partno=GRM155R60J106ME15%23"
			(at 335.28 19.05 0)
			(effects
				(font
					(size 1.27 1.27)
					(thickness 0.15)
				)
				(justify left bottom)
				(hide yes)
			)
		)
		(property "Description" ""
			(at 320.04 39.37 0)
			(effects
				(font
					(size 1.27 1.27)
				)
				(hide yes)
			)
		)
		(property "MPN" "GRM155R60J106ME15D"
			(at 337.82 19.05 0)
			(effects
				(font
					(size 1.27 1.27)
					(thickness 0.15)
				)
				(justify left bottom)
				(hide yes)
			)
		)
		(property "Manufacturer" "Murata"
			(at 340.36 19.05 0)
			(effects
				(font
					(size 1.27 1.27)
					(thickness 0.15)
				)
				(justify left bottom)
				(hide yes)
			)
		)
		(property "License" "Apache-2.0"
			(at 342.9 19.05 0)
			(effects
				(font
					(size 1.27 1.27)
					(thickness 0.15)
				)
				(justify left bottom)
				(hide yes)
			)
		)
		(property "Author" "Antmicro"
			(at 345.44 19.05 0)
			(effects
				(font
					(size 1.27 1.27)
					(thickness 0.15)
				)
				(justify left bottom)
				(hide yes)
			)
		)
		(property "Val" "10u"
			(at 322.3641 38.5167 90)
			(effects
				(font
					(size 1.27 1.27)
					(thickness 0.15)
				)
				(justify right)
			)
		)
		(property "Voltage" "6.3V"
			(at 347.98 19.05 0)
			(effects
				(font
					(size 1.27 1.27)
				)
				(justify left bottom)
				(hide yes)
			)
		)
		(property "Dielectric" "X5R"
			(at 350.52 19.05 0)
			(effects
				(font
					(size 1.27 1.27)
				)
				(justify left bottom)
				(hide yes)
			)
		)
		(pin "1"
		)
		(pin "2"
		)
		(instances
			(project "data-center-rdimm-ddr5-tester"
				(path ""
					(reference "C301")
					(unit 1)
				)
			)
		)
	)
	(symbol
		(lib_id "antmicropower:+3V3")
		(at 48.26 111.76 0)
		(unit 1)
		(exclude_from_sim no)
		(in_bom yes)
		(on_board yes)
		(dnp no)
		(fields_autoplaced yes)
		(property "Reference" "#PWR0489"
			(at 63.5 111.76 0)
			(effects
				(font
					(size 1.27 1.27)
					(thickness 0.15)
				)
				(justify left bottom)
				(hide yes)
			)
		)
		(property "Value" "+3V3"
			(at 48.26 108.585 0)
			(effects
				(font
					(size 1.27 1.27)
					(thickness 0.15)
				)
			)
		)
		(property "Footprint" ""
			(at 63.5 119.38 0)
			(effects
				(font
					(size 1.27 1.27)
					(thickness 0.15)
				)
				(justify left bottom)
				(hide yes)
			)
		)
		(property "Datasheet" ""
			(at 63.5 121.92 0)
			(effects
				(font
					(size 1.27 1.27)
					(thickness 0.15)
				)
				(justify left bottom)
				(hide yes)
			)
		)
		(property "Description" ""
			(at 48.26 111.76 0)
			(effects
				(font
					(size 1.27 1.27)
				)
				(hide yes)
			)
		)
		(property "Author" "Antmicro"
			(at 63.5 114.3 0)
			(effects
				(font
					(size 1.27 1.27)
					(thickness 0.15)
				)
				(justify left bottom)
				(hide yes)
			)
		)
		(property "License" "Apache-2.0"
			(at 63.5 116.84 0)
			(effects
				(font
					(size 1.27 1.27)
					(thickness 0.15)
				)
				(justify left bottom)
				(hide yes)
			)
		)
		(pin "1"
		)
		(instances
			(project "data-center-rdimm-ddr5-tester"
				(path ""
					(reference "#PWR0489")
					(unit 1)
				)
			)
		)
	)
	(symbol
		(lib_id "antmicropower:+1V8")
		(at 19.05 36.83 0)
		(unit 1)
		(exclude_from_sim no)
		(in_bom yes)
		(on_board yes)
		(dnp no)
		(property "Reference" "#PWR0485"
			(at 34.29 39.37 0)
			(effects
				(font
					(size 1.27 1.27)
					(thickness 0.15)
				)
				(justify left bottom)
				(hide yes)
			)
		)
		(property "Value" "+1V8"
			(at 19.05 33.02 0)
			(effects
				(font
					(size 1.27 1.27)
					(thickness 0.15)
				)
			)
		)
		(property "Footprint" ""
			(at 34.29 44.45 0)
			(effects
				(font
					(size 1.27 1.27)
					(thickness 0.15)
				)
				(justify left bottom)
				(hide yes)
			)
		)
		(property "Datasheet" ""
			(at 34.29 46.99 0)
			(effects
				(font
					(size 1.27 1.27)
					(thickness 0.15)
				)
				(justify left bottom)
				(hide yes)
			)
		)
		(property "Description" ""
			(at 19.05 36.83 0)
			(effects
				(font
					(size 1.27 1.27)
				)
				(hide yes)
			)
		)
		(property "Author" "Antmicro"
			(at 34.29 41.91 0)
			(effects
				(font
					(size 1.27 1.27)
					(thickness 0.15)
				)
				(justify left bottom)
				(hide yes)
			)
		)
		(property "License" "Apache-2.0"
			(at 34.29 44.45 0)
			(effects
				(font
					(size 1.27 1.27)
					(thickness 0.15)
				)
				(justify left bottom)
				(hide yes)
			)
		)
		(pin "1"
		)
		(instances
			(project "data-center-rdimm-ddr5-tester"
				(path ""
					(reference "#PWR0485")
					(unit 1)
				)
			)
		)
	)
	(symbol
		(lib_id "antmicroResistors0402:R_2k2_0402")
		(at 41.91 180.34 90)
		(unit 1)
		(exclude_from_sim no)
		(in_bom yes)
		(on_board yes)
		(dnp no)
		(property "Reference" "R237"
			(at 43.307 175.641 0)
			(effects
				(font
					(size 1.27 1.27)
					(thickness 0.15)
				)
				(justify left)
			)
		)
		(property "Value" "R_2k2_0402"
			(at 54.61 160.02 0)
			(effects
				(font
					(size 1.27 1.27)
					(thickness 0.15)
				)
				(justify left bottom)
				(hide yes)
			)
		)
		(property "Footprint" "antmicro-footprints:R_0402_1005Metric"
			(at 57.15 160.02 0)
			(effects
				(font
					(size 1.27 1.27)
					(thickness 0.15)
				)
				(justify left bottom)
				(hide yes)
			)
		)
		(property "Datasheet" "https://www.bourns.com/docs/product-datasheets/cr.pdf"
			(at 59.69 160.02 0)
			(effects
				(font
					(size 1.27 1.27)
					(thickness 0.15)
				)
				(justify left bottom)
				(hide yes)
			)
		)
		(property "Description" ""
			(at 41.91 180.34 0)
			(effects
				(font
					(size 1.27 1.27)
				)
				(hide yes)
			)
		)
		(property "MPN" "CR0402-FX-2201GLF"
			(at 62.23 160.02 0)
			(effects
				(font
					(size 1.27 1.27)
					(thickness 0.15)
				)
				(justify left bottom)
				(hide yes)
			)
		)
		(property "Manufacturer" "Bourns"
			(at 64.77 160.02 0)
			(effects
				(font
					(size 1.27 1.27)
					(thickness 0.15)
				)
				(justify left bottom)
				(hide yes)
			)
		)
		(property "License" "Apache-2.0"
			(at 67.31 160.02 0)
			(effects
				(font
					(size 1.27 1.27)
					(thickness 0.15)
				)
				(justify left bottom)
				(hide yes)
			)
		)
		(property "Author" "Antmicro"
			(at 69.85 160.02 0)
			(effects
				(font
					(size 1.27 1.27)
					(thickness 0.15)
				)
				(justify left bottom)
				(hide yes)
			)
		)
		(property "Val" "2k2"
			(at 43.434 183.642 0)
			(effects
				(font
					(size 1.27 1.27)
					(thickness 0.15)
				)
				(justify left)
			)
		)
		(property "Tolerance" "1%"
			(at 52.07 160.02 0)
			(effects
				(font
					(size 1.27 1.27)
				)
				(justify left bottom)
				(hide yes)
			)
		)
		(property "Public" ""
			(at 72.39 160.02 0)
			(effects
				(font
					(size 1.27 1.27)
				)
				(justify left bottom)
				(hide yes)
			)
		)
		(pin "1"
		)
		(pin "2"
		)
		(instances
			(project "data-center-rdimm-ddr5-tester"
				(path ""
					(reference "R237")
					(unit 1)
				)
			)
		)
	)
	(symbol
		(lib_id "antmicroTransistorsFETsMOSFETsSingle:BSS138PW")
		(at 361.95 125.73 0)
		(mirror y)
		(unit 1)
		(exclude_from_sim no)
		(in_bom yes)
		(on_board yes)
		(dnp no)
		(property "Reference" "Q21"
			(at 350.52 121.92 0)
			(effects
				(font
					(size 1.27 1.27)
				)
				(justify left)
			)
		)
		(property "Value" "BSS138PW"
			(at 351.536 124.8897 0)
			(effects
				(font
					(size 1.27 1.27)
					(thickness 0.15)
				)
				(justify left)
				(hide yes)
			)
		)
		(property "Footprint" "antmicro-footprints:SC70-3"
			(at 339.09 137.16 0)
			(effects
				(font
					(size 1.27 1.27)
					(thickness 0.15)
				)
				(justify left bottom)
				(hide yes)
			)
		)
		(property "Datasheet" "https://assets.nexperia.com/documents/data-sheet/BSS138PW.pdf"
			(at 339.09 139.7 0)
			(effects
				(font
					(size 1.27 1.27)
					(thickness 0.15)
				)
				(justify left bottom)
				(hide yes)
			)
		)
		(property "Description" ""
			(at 361.95 125.73 0)
			(effects
				(font
					(size 1.27 1.27)
				)
				(hide yes)
			)
		)
		(property "MPN" "BSS138PW"
			(at 350.52 124.46 0)
			(effects
				(font
					(size 1.27 1.27)
					(thickness 0.15)
				)
				(justify left)
			)
		)
		(property "Manufacturer" "Nexperia"
			(at 339.09 144.78 0)
			(effects
				(font
					(size 1.27 1.27)
					(thickness 0.15)
				)
				(justify left bottom)
				(hide yes)
			)
		)
		(property "Author" "Antmicro"
			(at 339.09 147.32 0)
			(effects
				(font
					(size 1.27 1.27)
					(thickness 0.15)
				)
				(justify left bottom)
				(hide yes)
			)
		)
		(property "License" "Apache-2.0"
			(at 339.09 149.86 0)
			(effects
				(font
					(size 1.27 1.27)
					(thickness 0.15)
				)
				(justify left bottom)
				(hide yes)
			)
		)
		(pin "1"
		)
		(pin "2"
		)
		(pin "3"
		)
		(instances
			(project "data-center-rdimm-ddr5-tester"
				(path ""
					(reference "Q21")
					(unit 1)
				)
			)
		)
	)
	(symbol
		(lib_id "antmicroResistors0402:R_64k9_0402")
		(at 71.12 264.16 180)
		(unit 1)
		(exclude_from_sim no)
		(in_bom yes)
		(on_board yes)
		(dnp no)
		(property "Reference" "R77"
			(at 71.12 262.89 0)
			(effects
				(font
					(size 1.27 1.27)
					(thickness 0.15)
				)
				(justify right)
			)
		)
		(property "Value" "R_64k9_0402"
			(at 50.8 251.46 0)
			(effects
				(font
					(size 1.27 1.27)
					(thickness 0.15)
				)
				(justify left bottom)
				(hide yes)
			)
		)
		(property "Footprint" "antmicro-footprints:R_0402_1005Metric"
			(at 50.8 248.92 0)
			(effects
				(font
					(size 1.27 1.27)
					(thickness 0.15)
				)
				(justify left bottom)
				(hide yes)
			)
		)
		(property "Datasheet" "https://www.bourns.com/docs/product-datasheets/cr.pdf"
			(at 50.8 246.38 0)
			(effects
				(font
					(size 1.27 1.27)
					(thickness 0.15)
				)
				(justify left bottom)
				(hide yes)
			)
		)
		(property "Description" ""
			(at 71.12 264.16 0)
			(effects
				(font
					(size 1.27 1.27)
				)
				(hide yes)
			)
		)
		(property "MPN" "CR0402-FX-6492GLF"
			(at 50.8 243.84 0)
			(effects
				(font
					(size 1.27 1.27)
					(thickness 0.15)
				)
				(justify left bottom)
				(hide yes)
			)
		)
		(property "Manufacturer" "Bourns"
			(at 50.8 241.3 0)
			(effects
				(font
					(size 1.27 1.27)
					(thickness 0.15)
				)
				(justify left bottom)
				(hide yes)
			)
		)
		(property "License" "Apache-2.0"
			(at 50.8 238.76 0)
			(effects
				(font
					(size 1.27 1.27)
					(thickness 0.15)
				)
				(justify left bottom)
				(hide yes)
			)
		)
		(property "Author" "Antmicro"
			(at 50.8 236.22 0)
			(effects
				(font
					(size 1.27 1.27)
					(thickness 0.15)
				)
				(justify left bottom)
				(hide yes)
			)
		)
		(property "Val" "64k9"
			(at 60.96 262.89 0)
			(effects
				(font
					(size 1.27 1.27)
					(thickness 0.15)
				)
				(justify right)
			)
		)
		(property "Tolerance" "1%"
			(at 50.8 254 0)
			(effects
				(font
					(size 1.27 1.27)
				)
				(justify left bottom)
				(hide yes)
			)
		)
		(pin "2"
		)
		(pin "1"
		)
		(instances
			(project "data-center-rdimm-ddr5-tester"
				(path ""
					(reference "R77")
					(unit 1)
				)
			)
		)
	)
	(symbol
		(lib_id "antmicropower:GND")
		(at 177.8 60.96 0)
		(unit 1)
		(exclude_from_sim no)
		(in_bom yes)
		(on_board yes)
		(dnp no)
		(fields_autoplaced yes)
		(property "Reference" "#PWR0217"
			(at 177.8 67.31 0)
			(effects
				(font
					(size 1.27 1.27)
				)
				(hide yes)
			)
		)
		(property "Value" "GND"
			(at 175.895 65.405 0)
			(effects
				(font
					(size 1.27 1.27)
					(thickness 0.15)
				)
				(justify left bottom)
			)
		)
		(property "Footprint" ""
			(at 186.69 68.58 0)
			(effects
				(font
					(size 1.27 1.27)
					(thickness 0.15)
				)
				(justify left bottom)
				(hide yes)
			)
		)
		(property "Datasheet" ""
			(at 186.69 73.66 0)
			(effects
				(font
					(size 1.27 1.27)
					(thickness 0.15)
				)
				(justify left bottom)
				(hide yes)
			)
		)
		(property "Description" ""
			(at 177.8 60.96 0)
			(effects
				(font
					(size 1.27 1.27)
				)
				(hide yes)
			)
		)
		(property "Author" "Antmicro"
			(at 186.69 66.04 0)
			(effects
				(font
					(size 1.27 1.27)
					(thickness 0.15)
				)
				(justify left bottom)
				(hide yes)
			)
		)
		(property "License" "Apache-2.0"
			(at 186.69 68.58 0)
			(effects
				(font
					(size 1.27 1.27)
					(thickness 0.15)
				)
				(justify left bottom)
				(hide yes)
			)
		)
		(pin "1"
		)
		(instances
			(project "data-center-rdimm-ddr5-tester"
				(path ""
					(reference "#PWR0217")
					(unit 1)
				)
			)
		)
	)
	(symbol
		(lib_id "antmicropower:GND")
		(at 300.99 110.49 0)
		(mirror y)
		(unit 1)
		(exclude_from_sim no)
		(in_bom yes)
		(on_board yes)
		(dnp no)
		(fields_autoplaced yes)
		(property "Reference" "#PWR0472"
			(at 300.99 116.84 0)
			(effects
				(font
					(size 1.27 1.27)
				)
				(hide yes)
			)
		)
		(property "Value" "GND"
			(at 302.895 114.935 0)
			(effects
				(font
					(size 1.27 1.27)
					(thickness 0.15)
				)
				(justify left bottom)
			)
		)
		(property "Footprint" ""
			(at 292.1 118.11 0)
			(effects
				(font
					(size 1.27 1.27)
					(thickness 0.15)
				)
				(justify left bottom)
				(hide yes)
			)
		)
		(property "Datasheet" ""
			(at 292.1 123.19 0)
			(effects
				(font
					(size 1.27 1.27)
					(thickness 0.15)
				)
				(justify left bottom)
				(hide yes)
			)
		)
		(property "Description" ""
			(at 300.99 110.49 0)
			(effects
				(font
					(size 1.27 1.27)
				)
				(hide yes)
			)
		)
		(property "Author" "Antmicro"
			(at 292.1 115.57 0)
			(effects
				(font
					(size 1.27 1.27)
					(thickness 0.15)
				)
				(justify left bottom)
				(hide yes)
			)
		)
		(property "License" "Apache-2.0"
			(at 292.1 118.11 0)
			(effects
				(font
					(size 1.27 1.27)
					(thickness 0.15)
				)
				(justify left bottom)
				(hide yes)
			)
		)
		(pin "1"
		)
		(instances
			(project "data-center-rdimm-ddr5-tester"
				(path ""
					(reference "#PWR0472")
					(unit 1)
				)
			)
		)
	)
	(symbol
		(lib_id "antmicroCapacitors0402:C_100n_0402")
		(at 158.75 264.16 270)
		(unit 1)
		(exclude_from_sim no)
		(in_bom yes)
		(on_board yes)
		(dnp no)
		(property "Reference" "C281"
			(at 157.48 270.51 0)
			(effects
				(font
					(size 1.27 1.27)
					(thickness 0.15)
				)
			)
		)
		(property "Value" "C_100n_0402"
			(at 148.59 284.48 0)
			(effects
				(font
					(size 1.27 1.27)
					(thickness 0.15)
				)
				(justify left bottom)
				(hide yes)
			)
		)
		(property "Footprint" "antmicro-footprints:C_0402_1005Metric"
			(at 146.05 284.48 0)
			(effects
				(font
					(size 1.27 1.27)
					(thickness 0.15)
				)
				(justify left bottom)
				(hide yes)
			)
		)
		(property "Datasheet" "https://www.murata.com/products/productdetail?partno=GRM155R61H104KE14%23"
			(at 143.51 284.48 0)
			(effects
				(font
					(size 1.27 1.27)
					(thickness 0.15)
				)
				(justify left bottom)
				(hide yes)
			)
		)
		(property "Description" ""
			(at 158.75 264.16 0)
			(effects
				(font
					(size 1.27 1.27)
				)
				(hide yes)
			)
		)
		(property "MPN" "GRM155R61H104KE14D"
			(at 140.97 284.48 0)
			(effects
				(font
					(size 1.27 1.27)
					(thickness 0.15)
				)
				(justify left bottom)
				(hide yes)
			)
		)
		(property "Manufacturer" "Murata"
			(at 138.43 284.48 0)
			(effects
				(font
					(size 1.27 1.27)
					(thickness 0.15)
				)
				(justify left bottom)
				(hide yes)
			)
		)
		(property "License" "Apache-2.0"
			(at 135.89 284.48 0)
			(effects
				(font
					(size 1.27 1.27)
					(thickness 0.15)
				)
				(justify left bottom)
				(hide yes)
			)
		)
		(property "Author" "Antmicro"
			(at 133.35 284.48 0)
			(effects
				(font
					(size 1.27 1.27)
					(thickness 0.15)
				)
				(justify left bottom)
				(hide yes)
			)
		)
		(property "Val" "100n"
			(at 156.21 260.35 0)
			(effects
				(font
					(size 1.27 1.27)
					(thickness 0.15)
				)
				(justify left bottom)
			)
		)
		(property "Voltage" "50V"
			(at 130.81 284.48 0)
			(effects
				(font
					(size 1.27 1.27)
				)
				(justify left bottom)
				(hide yes)
			)
		)
		(property "Dielectric" "X5R"
			(at 128.27 284.48 0)
			(effects
				(font
					(size 1.27 1.27)
				)
				(justify left bottom)
				(hide yes)
			)
		)
		(property "Public" ""
			(at 125.73 284.48 0)
			(effects
				(font
					(size 1.27 1.27)
				)
				(justify left bottom)
				(hide yes)
			)
		)
		(pin "2"
		)
		(pin "1"
		)
		(instances
			(project "data-center-rdimm-ddr5-tester"
				(path ""
					(reference "C281")
					(unit 1)
				)
			)
		)
	)
	(symbol
		(lib_id "antmicroCapacitors0402:C_100n_0402")
		(at 148.59 264.16 270)
		(unit 1)
		(exclude_from_sim no)
		(in_bom yes)
		(on_board yes)
		(dnp no)
		(property "Reference" "C278"
			(at 147.32 270.51 0)
			(effects
				(font
					(size 1.27 1.27)
					(thickness 0.15)
				)
			)
		)
		(property "Value" "C_100n_0402"
			(at 138.43 284.48 0)
			(effects
				(font
					(size 1.27 1.27)
					(thickness 0.15)
				)
				(justify left bottom)
				(hide yes)
			)
		)
		(property "Footprint" "antmicro-footprints:C_0402_1005Metric"
			(at 135.89 284.48 0)
			(effects
				(font
					(size 1.27 1.27)
					(thickness 0.15)
				)
				(justify left bottom)
				(hide yes)
			)
		)
		(property "Datasheet" "https://www.murata.com/products/productdetail?partno=GRM155R61H104KE14%23"
			(at 133.35 284.48 0)
			(effects
				(font
					(size 1.27 1.27)
					(thickness 0.15)
				)
				(justify left bottom)
				(hide yes)
			)
		)
		(property "Description" ""
			(at 148.59 264.16 0)
			(effects
				(font
					(size 1.27 1.27)
				)
				(hide yes)
			)
		)
		(property "MPN" "GRM155R61H104KE14D"
			(at 130.81 284.48 0)
			(effects
				(font
					(size 1.27 1.27)
					(thickness 0.15)
				)
				(justify left bottom)
				(hide yes)
			)
		)
		(property "Manufacturer" "Murata"
			(at 128.27 284.48 0)
			(effects
				(font
					(size 1.27 1.27)
					(thickness 0.15)
				)
				(justify left bottom)
				(hide yes)
			)
		)
		(property "License" "Apache-2.0"
			(at 125.73 284.48 0)
			(effects
				(font
					(size 1.27 1.27)
					(thickness 0.15)
				)
				(justify left bottom)
				(hide yes)
			)
		)
		(property "Author" "Antmicro"
			(at 123.19 284.48 0)
			(effects
				(font
					(size 1.27 1.27)
					(thickness 0.15)
				)
				(justify left bottom)
				(hide yes)
			)
		)
		(property "Val" "100n"
			(at 146.05 260.35 0)
			(effects
				(font
					(size 1.27 1.27)
					(thickness 0.15)
				)
				(justify left bottom)
			)
		)
		(property "Voltage" "50V"
			(at 120.65 284.48 0)
			(effects
				(font
					(size 1.27 1.27)
				)
				(justify left bottom)
				(hide yes)
			)
		)
		(property "Dielectric" "X5R"
			(at 118.11 284.48 0)
			(effects
				(font
					(size 1.27 1.27)
				)
				(justify left bottom)
				(hide yes)
			)
		)
		(property "Public" ""
			(at 115.57 284.48 0)
			(effects
				(font
					(size 1.27 1.27)
				)
				(justify left bottom)
				(hide yes)
			)
		)
		(pin "2"
		)
		(pin "1"
		)
		(instances
			(project "data-center-rdimm-ddr5-tester"
				(path ""
					(reference "C278")
					(unit 1)
				)
			)
		)
	)
	(symbol
		(lib_id "antmicropower:GND")
		(at 80.01 232.41 0)
		(unit 1)
		(exclude_from_sim no)
		(in_bom yes)
		(on_board yes)
		(dnp no)
		(fields_autoplaced yes)
		(property "Reference" "#PWR0466"
			(at 88.9 234.95 0)
			(effects
				(font
					(size 1.27 1.27)
					(thickness 0.15)
				)
				(justify left bottom)
				(hide yes)
			)
		)
		(property "Value" "GND"
			(at 80.01 236.855 0)
			(effects
				(font
					(size 1.27 1.27)
					(thickness 0.15)
				)
			)
		)
		(property "Footprint" ""
			(at 88.9 240.03 0)
			(effects
				(font
					(size 1.27 1.27)
					(thickness 0.15)
				)
				(justify left bottom)
				(hide yes)
			)
		)
		(property "Datasheet" ""
			(at 88.9 245.11 0)
			(effects
				(font
					(size 1.27 1.27)
					(thickness 0.15)
				)
				(justify left bottom)
				(hide yes)
			)
		)
		(property "Description" ""
			(at 80.01 232.41 0)
			(effects
				(font
					(size 1.27 1.27)
				)
				(hide yes)
			)
		)
		(property "Author" "Antmicro"
			(at 88.9 240.03 0)
			(effects
				(font
					(size 1.27 1.27)
					(thickness 0.15)
				)
				(justify left bottom)
				(hide yes)
			)
		)
		(property "License" "Apache-2.0"
			(at 88.9 242.57 0)
			(effects
				(font
					(size 1.27 1.27)
					(thickness 0.15)
				)
				(justify left bottom)
				(hide yes)
			)
		)
		(pin "1"
		)
		(instances
			(project "data-center-rdimm-ddr5-tester"
				(path ""
					(reference "#PWR0466")
					(unit 1)
				)
			)
		)
	)
	(symbol
		(lib_id "antmicropower:+3V3")
		(at 80.01 153.67 0)
		(unit 1)
		(exclude_from_sim no)
		(in_bom yes)
		(on_board yes)
		(dnp no)
		(fields_autoplaced yes)
		(property "Reference" "#PWR0465"
			(at 95.25 153.67 0)
			(effects
				(font
					(size 1.27 1.27)
					(thickness 0.15)
				)
				(justify left bottom)
				(hide yes)
			)
		)
		(property "Value" "+3V3"
			(at 80.01 148.59 0)
			(effects
				(font
					(size 1.27 1.27)
					(thickness 0.15)
				)
			)
		)
		(property "Footprint" ""
			(at 95.25 161.29 0)
			(effects
				(font
					(size 1.27 1.27)
					(thickness 0.15)
				)
				(justify left bottom)
				(hide yes)
			)
		)
		(property "Datasheet" ""
			(at 95.25 163.83 0)
			(effects
				(font
					(size 1.27 1.27)
					(thickness 0.15)
				)
				(justify left bottom)
				(hide yes)
			)
		)
		(property "Description" ""
			(at 80.01 153.67 0)
			(effects
				(font
					(size 1.27 1.27)
				)
				(hide yes)
			)
		)
		(property "Author" "Antmicro"
			(at 95.25 156.21 0)
			(effects
				(font
					(size 1.27 1.27)
					(thickness 0.15)
				)
				(justify left bottom)
				(hide yes)
			)
		)
		(property "License" "Apache-2.0"
			(at 95.25 158.75 0)
			(effects
				(font
					(size 1.27 1.27)
					(thickness 0.15)
				)
				(justify left bottom)
				(hide yes)
			)
		)
		(pin "1"
		)
		(instances
			(project "data-center-rdimm-ddr5-tester"
				(path ""
					(reference "#PWR0465")
					(unit 1)
				)
			)
		)
	)
	(symbol
		(lib_id "antmicroResistors0402:R_49k9_0402")
		(at 386.08 38.1 90)
		(unit 1)
		(exclude_from_sim no)
		(in_bom yes)
		(on_board yes)
		(dnp no)
		(fields_autoplaced yes)
		(property "Reference" "R30"
			(at 387.985 34.29 90)
			(effects
				(font
					(size 1.27 1.27)
					(thickness 0.15)
				)
				(justify right)
			)
		)
		(property "Value" "R_49k9_0402"
			(at 398.78 17.78 0)
			(effects
				(font
					(size 1.27 1.27)
					(thickness 0.15)
				)
				(justify left bottom)
				(hide yes)
			)
		)
		(property "Footprint" "antmicro-footprints:R_0402_1005Metric"
			(at 401.32 17.78 0)
			(effects
				(font
					(size 1.27 1.27)
					(thickness 0.15)
				)
				(justify left bottom)
				(hide yes)
			)
		)
		(property "Datasheet" "https://www.bourns.com/docs/product-datasheets/cr.pdf"
			(at 403.86 17.78 0)
			(effects
				(font
					(size 1.27 1.27)
					(thickness 0.15)
				)
				(justify left bottom)
				(hide yes)
			)
		)
		(property "Description" ""
			(at 386.08 38.1 0)
			(effects
				(font
					(size 1.27 1.27)
				)
				(hide yes)
			)
		)
		(property "MPN" "CR0402-FX-4992GLF"
			(at 406.4 17.78 0)
			(effects
				(font
					(size 1.27 1.27)
					(thickness 0.15)
				)
				(justify left bottom)
				(hide yes)
			)
		)
		(property "Manufacturer" "Bourns"
			(at 408.94 17.78 0)
			(effects
				(font
					(size 1.27 1.27)
					(thickness 0.15)
				)
				(justify left bottom)
				(hide yes)
			)
		)
		(property "License" "Apache-2.0"
			(at 411.48 17.78 0)
			(effects
				(font
					(size 1.27 1.27)
					(thickness 0.15)
				)
				(justify left bottom)
				(hide yes)
			)
		)
		(property "Author" "Antmicro"
			(at 414.02 17.78 0)
			(effects
				(font
					(size 1.27 1.27)
					(thickness 0.15)
				)
				(justify left bottom)
				(hide yes)
			)
		)
		(property "Val" "49k9"
			(at 387.985 36.83 90)
			(effects
				(font
					(size 1.27 1.27)
					(thickness 0.15)
				)
				(justify right)
			)
		)
		(property "Tolerance" "1%"
			(at 396.24 17.78 0)
			(effects
				(font
					(size 1.27 1.27)
				)
				(justify left bottom)
				(hide yes)
			)
		)
		(pin "1"
		)
		(pin "2"
		)
		(instances
			(project "data-center-rdimm-ddr5-tester"
				(path ""
					(reference "R30")
					(unit 1)
				)
			)
		)
	)
	(symbol
		(lib_id "antmicroFixedInductors:L_20n_0.35A_0402")
		(at 328.93 45.72 90)
		(unit 1)
		(exclude_from_sim no)
		(in_bom yes)
		(on_board yes)
		(dnp no)
		(property "Reference" "L7"
			(at 330.2 41.91 90)
			(effects
				(font
					(size 1.27 1.27)
					(thickness 0.15)
				)
				(justify right)
			)
		)
		(property "Value" "L_20n_0.35A_0402"
			(at 331.47 31.75 0)
			(effects
				(font
					(size 1.27 1.27)
					(thickness 0.15)
				)
				(justify left bottom)
				(hide yes)
			)
		)
		(property "Footprint" "antmicro-footprints:L_0402_1005Metric"
			(at 336.55 31.75 0)
			(effects
				(font
					(size 1.27 1.27)
					(thickness 0.15)
				)
				(justify left bottom)
				(hide yes)
			)
		)
		(property "Datasheet" "https://product.tdk.com/system/files/dam/doc/product/inductor/inductor/smd/catalog/inductor_automotive_high-frequency_mlg1005s_en.pdf?ref_disty=mouser"
			(at 339.09 31.75 0)
			(effects
				(font
					(size 1.27 1.27)
					(thickness 0.15)
				)
				(justify left bottom)
				(hide yes)
			)
		)
		(property "Description" ""
			(at 328.93 45.72 0)
			(effects
				(font
					(size 1.27 1.27)
				)
				(hide yes)
			)
		)
		(property "Val" "20n/0.35A"
			(at 326.39 40.005 0)
			(effects
				(font
					(size 1.27 1.27)
					(thickness 0.15)
				)
				(justify right)
			)
		)
		(property "Manufacturer" "TDK"
			(at 341.63 31.75 0)
			(effects
				(font
					(size 1.27 1.27)
					(thickness 0.15)
				)
				(justify left bottom)
				(hide yes)
			)
		)
		(property "MPN" "MLG1005S20NJTD25"
			(at 344.17 31.75 0)
			(effects
				(font
					(size 1.27 1.27)
					(thickness 0.15)
				)
				(justify left bottom)
				(hide yes)
			)
		)
		(property "ISat" ""
			(at 345.44 31.75 0)
			(effects
				(font
					(size 1.27 1.27)
				)
				(justify left)
				(hide yes)
			)
		)
		(property "IMax" "0.35 A"
			(at 349.25 31.75 0)
			(effects
				(font
					(size 1.27 1.27)
					(thickness 0.15)
				)
				(justify left bottom)
				(hide yes)
			)
		)
		(property "Size" "1.0x0.5"
			(at 351.79 31.75 0)
			(effects
				(font
					(size 1.27 1.27)
					(thickness 0.15)
				)
				(justify left bottom)
				(hide yes)
			)
		)
		(property "Author" "Antmicro"
			(at 354.33 31.75 0)
			(effects
				(font
					(size 1.27 1.27)
					(thickness 0.15)
				)
				(justify left bottom)
				(hide yes)
			)
		)
		(property "License" "Apache-2.0"
			(at 356.87 31.75 0)
			(effects
				(font
					(size 1.27 1.27)
					(thickness 0.15)
				)
				(justify left bottom)
				(hide yes)
			)
		)
		(pin "2"
		)
		(pin "1"
		)
		(instances
			(project "data-center-rdimm-ddr5-tester"
				(path ""
					(reference "L7")
					(unit 1)
				)
			)
		)
	)
	(symbol
		(lib_id "antmicropower:+3V3")
		(at 299.72 31.75 0)
		(unit 1)
		(exclude_from_sim no)
		(in_bom yes)
		(on_board yes)
		(dnp no)
		(fields_autoplaced yes)
		(property "Reference" "#PWR0198"
			(at 314.96 31.75 0)
			(effects
				(font
					(size 1.27 1.27)
					(thickness 0.15)
				)
				(justify left bottom)
				(hide yes)
			)
		)
		(property "Value" "+3V3"
			(at 299.72 26.67 0)
			(effects
				(font
					(size 1.27 1.27)
					(thickness 0.15)
				)
			)
		)
		(property "Footprint" ""
			(at 314.96 39.37 0)
			(effects
				(font
					(size 1.27 1.27)
					(thickness 0.15)
				)
				(justify left bottom)
				(hide yes)
			)
		)
		(property "Datasheet" ""
			(at 314.96 41.91 0)
			(effects
				(font
					(size 1.27 1.27)
					(thickness 0.15)
				)
				(justify left bottom)
				(hide yes)
			)
		)
		(property "Description" ""
			(at 299.72 31.75 0)
			(effects
				(font
					(size 1.27 1.27)
				)
				(hide yes)
			)
		)
		(property "Author" "Antmicro"
			(at 314.96 34.29 0)
			(effects
				(font
					(size 1.27 1.27)
					(thickness 0.15)
				)
				(justify left bottom)
				(hide yes)
			)
		)
		(property "License" "Apache-2.0"
			(at 314.96 36.83 0)
			(effects
				(font
					(size 1.27 1.27)
					(thickness 0.15)
				)
				(justify left bottom)
				(hide yes)
			)
		)
		(pin "1"
		)
		(instances
			(project "data-center-rdimm-ddr5-tester"
				(path ""
					(reference "#PWR0198")
					(unit 1)
				)
			)
		)
	)
	(symbol
		(lib_id "antmicroResistors0402:R_2k2_0402")
		(at 44.45 180.34 90)
		(unit 1)
		(exclude_from_sim no)
		(in_bom yes)
		(on_board yes)
		(dnp no)
		(property "Reference" "R236"
			(at 45.847 175.641 0)
			(effects
				(font
					(size 1.27 1.27)
					(thickness 0.15)
				)
				(justify left)
			)
		)
		(property "Value" "R_2k2_0402"
			(at 57.15 160.02 0)
			(effects
				(font
					(size 1.27 1.27)
					(thickness 0.15)
				)
				(justify left bottom)
				(hide yes)
			)
		)
		(property "Footprint" "antmicro-footprints:R_0402_1005Metric"
			(at 59.69 160.02 0)
			(effects
				(font
					(size 1.27 1.27)
					(thickness 0.15)
				)
				(justify left bottom)
				(hide yes)
			)
		)
		(property "Datasheet" "https://www.bourns.com/docs/product-datasheets/cr.pdf"
			(at 62.23 160.02 0)
			(effects
				(font
					(size 1.27 1.27)
					(thickness 0.15)
				)
				(justify left bottom)
				(hide yes)
			)
		)
		(property "Description" ""
			(at 44.45 180.34 0)
			(effects
				(font
					(size 1.27 1.27)
				)
				(hide yes)
			)
		)
		(property "MPN" "CR0402-FX-2201GLF"
			(at 64.77 160.02 0)
			(effects
				(font
					(size 1.27 1.27)
					(thickness 0.15)
				)
				(justify left bottom)
				(hide yes)
			)
		)
		(property "Manufacturer" "Bourns"
			(at 67.31 160.02 0)
			(effects
				(font
					(size 1.27 1.27)
					(thickness 0.15)
				)
				(justify left bottom)
				(hide yes)
			)
		)
		(property "License" "Apache-2.0"
			(at 69.85 160.02 0)
			(effects
				(font
					(size 1.27 1.27)
					(thickness 0.15)
				)
				(justify left bottom)
				(hide yes)
			)
		)
		(property "Author" "Antmicro"
			(at 72.39 160.02 0)
			(effects
				(font
					(size 1.27 1.27)
					(thickness 0.15)
				)
				(justify left bottom)
				(hide yes)
			)
		)
		(property "Val" "2k2"
			(at 45.974 183.642 0)
			(effects
				(font
					(size 1.27 1.27)
					(thickness 0.15)
				)
				(justify left)
			)
		)
		(property "Tolerance" "1%"
			(at 54.61 160.02 0)
			(effects
				(font
					(size 1.27 1.27)
				)
				(justify left bottom)
				(hide yes)
			)
		)
		(property "Public" ""
			(at 74.93 160.02 0)
			(effects
				(font
					(size 1.27 1.27)
				)
				(justify left bottom)
				(hide yes)
			)
		)
		(pin "1"
		)
		(pin "2"
		)
		(instances
			(project "data-center-rdimm-ddr5-tester"
				(path ""
					(reference "R236")
					(unit 1)
				)
			)
		)
	)
	(symbol
		(lib_id "antmicropower:+1V2")
		(at 137.16 251.46 0)
		(unit 1)
		(exclude_from_sim no)
		(in_bom yes)
		(on_board yes)
		(dnp no)
		(property "Reference" "#PWR0272"
			(at 137.16 255.27 0)
			(effects
				(font
					(size 1.27 1.27)
				)
				(hide yes)
			)
		)
		(property "Value" "+1V2"
			(at 137.16 247.65 0)
			(effects
				(font
					(size 1.27 1.27)
				)
			)
		)
		(property "Footprint" ""
			(at 137.16 251.46 0)
			(effects
				(font
					(size 1.27 1.27)
				)
				(hide yes)
			)
		)
		(property "Datasheet" ""
			(at 137.16 251.46 0)
			(effects
				(font
					(size 1.27 1.27)
				)
				(hide yes)
			)
		)
		(property "Description" ""
			(at 137.16 251.46 0)
			(effects
				(font
					(size 1.27 1.27)
				)
				(hide yes)
			)
		)
		(pin "1"
		)
		(instances
			(project "data-center-rdimm-ddr5-tester"
				(path ""
					(reference "#PWR0272")
					(unit 1)
				)
			)
		)
	)
	(symbol
		(lib_id "antmicropower:+3V3")
		(at 27.94 259.08 0)
		(unit 1)
		(exclude_from_sim no)
		(in_bom yes)
		(on_board yes)
		(dnp no)
		(fields_autoplaced yes)
		(property "Reference" "#PWR0467"
			(at 43.18 259.08 0)
			(effects
				(font
					(size 1.27 1.27)
					(thickness 0.15)
				)
				(justify left bottom)
				(hide yes)
			)
		)
		(property "Value" "+3V3"
			(at 27.94 254 0)
			(effects
				(font
					(size 1.27 1.27)
					(thickness 0.15)
				)
			)
		)
		(property "Footprint" ""
			(at 43.18 266.7 0)
			(effects
				(font
					(size 1.27 1.27)
					(thickness 0.15)
				)
				(justify left bottom)
				(hide yes)
			)
		)
		(property "Datasheet" ""
			(at 43.18 269.24 0)
			(effects
				(font
					(size 1.27 1.27)
					(thickness 0.15)
				)
				(justify left bottom)
				(hide yes)
			)
		)
		(property "Description" ""
			(at 27.94 259.08 0)
			(effects
				(font
					(size 1.27 1.27)
				)
				(hide yes)
			)
		)
		(property "Author" "Antmicro"
			(at 43.18 261.62 0)
			(effects
				(font
					(size 1.27 1.27)
					(thickness 0.15)
				)
				(justify left bottom)
				(hide yes)
			)
		)
		(property "License" "Apache-2.0"
			(at 43.18 264.16 0)
			(effects
				(font
					(size 1.27 1.27)
					(thickness 0.15)
				)
				(justify left bottom)
				(hide yes)
			)
		)
		(pin "1"
		)
		(instances
			(project "data-center-rdimm-ddr5-tester"
				(path ""
					(reference "#PWR0467")
					(unit 1)
				)
			)
		)
	)
	(symbol
		(lib_id "antmicroTestPoints:TP_1mm_SMD")
		(at 194.31 214.63 90)
		(unit 1)
		(exclude_from_sim no)
		(in_bom no)
		(on_board yes)
		(dnp no)
		(fields_autoplaced yes)
		(property "Reference" "TP2"
			(at 194.31 209.6572 90)
			(effects
				(font
					(size 1.27 1.27)
				)
			)
		)
		(property "Value" "TP_1mm_SMD"
			(at 201.93 199.39 0)
			(effects
				(font
					(size 1.27 1.27)
					(thickness 0.15)
				)
				(justify left bottom)
				(hide yes)
			)
		)
		(property "Footprint" "antmicro-footprints:TP_SMD_1mm"
			(at 204.47 199.39 0)
			(effects
				(font
					(size 1.27 1.27)
					(thickness 0.15)
				)
				(justify left bottom)
				(hide yes)
			)
		)
		(property "Datasheet" ""
			(at 207.01 199.39 0)
			(effects
				(font
					(size 1.27 1.27)
					(thickness 0.15)
				)
				(justify left bottom)
				(hide yes)
			)
		)
		(property "Description" ""
			(at 194.31 214.63 0)
			(effects
				(font
					(size 1.27 1.27)
				)
				(hide yes)
			)
		)
		(property "MPN" ""
			(at 194.31 214.63 0)
			(effects
				(font
					(size 1.27 1.27)
				)
				(hide yes)
			)
		)
		(property "Manufacturer" ""
			(at 194.31 214.63 0)
			(effects
				(font
					(size 1.27 1.27)
				)
				(hide yes)
			)
		)
		(property "Author" "Antmicro"
			(at 209.55 199.39 0)
			(effects
				(font
					(size 1.27 1.27)
					(thickness 0.15)
				)
				(justify left bottom)
				(hide yes)
			)
		)
		(property "License" "Apache-2.0"
			(at 212.09 199.39 0)
			(effects
				(font
					(size 1.27 1.27)
					(thickness 0.15)
				)
				(justify left bottom)
				(hide yes)
			)
		)
		(pin "1"
		)
		(instances
			(project "data-center-rdimm-ddr5-tester"
				(path ""
					(reference "TP2")
					(unit 1)
				)
			)
		)
	)
	(symbol
		(lib_id "antmicroLogicTranslatorsLevelShifters:TXS0102DQER")
		(at 340.36 160.02 0)
		(unit 1)
		(exclude_from_sim no)
		(in_bom yes)
		(on_board yes)
		(dnp no)
		(property "Reference" "U44"
			(at 349.25 156.21 0)
			(effects
				(font
					(size 1.27 1.27)
					(thickness 0.15)
				)
			)
		)
		(property "Value" "TXS0102DQER"
			(at 349.25 158.115 0)
			(effects
				(font
					(size 1.27 1.27)
					(thickness 0.15)
				)
				(hide yes)
			)
		)
		(property "Footprint" "antmicro-footprints:X2SON8_1.4x1x0.32mm_P0.35mm"
			(at 373.38 170.18 0)
			(effects
				(font
					(size 1.27 1.27)
					(thickness 0.15)
				)
				(justify left bottom)
				(hide yes)
			)
		)
		(property "Datasheet" "https://www.ti.com/lit/ds/symlink/txs0102.pdf?ts=1637914596981&ref_url=https%253A%252F%252Fwww.ti.com%252Fstore%252Fti%252Fen%252Fp%252Fproduct%252F%253Fp%253DTXS0102DCTR%2526keyMatch%253DTXS0102DCTR%2526tisearch%253Dsearch-everything%2526usecase%253DOPN"
			(at 373.38 172.72 0)
			(effects
				(font
					(size 1.27 1.27)
					(thickness 0.15)
				)
				(justify left bottom)
				(hide yes)
			)
		)
		(property "Description" ""
			(at 340.36 160.02 0)
			(effects
				(font
					(size 1.27 1.27)
				)
				(hide yes)
			)
		)
		(property "MPN" "TXS0102DQER"
			(at 349.25 158.75 0)
			(effects
				(font
					(size 1.27 1.27)
					(thickness 0.15)
				)
			)
		)
		(property "Manufacturer" "Texas Instruments"
			(at 373.38 177.8 0)
			(effects
				(font
					(size 1.27 1.27)
					(thickness 0.15)
				)
				(justify left bottom)
				(hide yes)
			)
		)
		(property "Author" "Antmicro"
			(at 373.38 180.34 0)
			(effects
				(font
					(size 1.27 1.27)
					(thickness 0.15)
				)
				(justify left bottom)
				(hide yes)
			)
		)
		(property "License" "Apache-2.0"
			(at 373.38 182.88 0)
			(effects
				(font
					(size 1.27 1.27)
					(thickness 0.15)
				)
				(justify left bottom)
				(hide yes)
			)
		)
		(pin "3"
		)
		(pin "8"
		)
		(pin "7"
		)
		(pin "4"
		)
		(pin "2"
		)
		(pin "1"
		)
		(pin "5"
		)
		(pin "6"
		)
		(instances
			(project "data-center-rdimm-ddr5-tester"
				(path ""
					(reference "U44")
					(unit 1)
				)
			)
		)
	)
	(symbol
		(lib_id "antmicropower:+1V8")
		(at 34.29 107.95 0)
		(unit 1)
		(exclude_from_sim no)
		(in_bom yes)
		(on_board yes)
		(dnp no)
		(fields_autoplaced yes)
		(property "Reference" "#PWR0493"
			(at 49.53 110.49 0)
			(effects
				(font
					(size 1.27 1.27)
					(thickness 0.15)
				)
				(justify left bottom)
				(hide yes)
			)
		)
		(property "Value" "+1V8"
			(at 34.29 104.14 0)
			(effects
				(font
					(size 1.27 1.27)
					(thickness 0.15)
				)
			)
		)
		(property "Footprint" ""
			(at 49.53 115.57 0)
			(effects
				(font
					(size 1.27 1.27)
					(thickness 0.15)
				)
				(justify left bottom)
				(hide yes)
			)
		)
		(property "Datasheet" ""
			(at 49.53 118.11 0)
			(effects
				(font
					(size 1.27 1.27)
					(thickness 0.15)
				)
				(justify left bottom)
				(hide yes)
			)
		)
		(property "Description" ""
			(at 34.29 107.95 0)
			(effects
				(font
					(size 1.27 1.27)
				)
				(hide yes)
			)
		)
		(property "Author" "Antmicro"
			(at 49.53 113.03 0)
			(effects
				(font
					(size 1.27 1.27)
					(thickness 0.15)
				)
				(justify left bottom)
				(hide yes)
			)
		)
		(property "License" "Apache-2.0"
			(at 49.53 115.57 0)
			(effects
				(font
					(size 1.27 1.27)
					(thickness 0.15)
				)
				(justify left bottom)
				(hide yes)
			)
		)
		(pin "1"
		)
		(instances
			(project "data-center-rdimm-ddr5-tester"
				(path ""
					(reference "#PWR0493")
					(unit 1)
				)
			)
		)
	)
	(symbol
		(lib_id "antmicroInterfaceDriversReceiversTransceivers:SN65DP159RGZR")
		(at 81.28 156.21 0)
		(unit 1)
		(exclude_from_sim no)
		(in_bom yes)
		(on_board yes)
		(dnp no)
		(fields_autoplaced yes)
		(property "Reference" "U38"
			(at 95.25 148.59 0)
			(effects
				(font
					(size 1.27 1.27)
					(thickness 0.15)
				)
			)
		)
		(property "Value" "SN65DP159RGZR"
			(at 132.08 161.29 0)
			(effects
				(font
					(size 1.27 1.27)
					(thickness 0.15)
				)
				(justify left bottom)
				(hide yes)
			)
		)
		(property "Footprint" "antmicro-footprints:VQFN-48_7x7mm_P0.5mm_EP4.1x4.1mm"
			(at 132.08 163.83 0)
			(effects
				(font
					(size 1.27 1.27)
					(thickness 0.15)
				)
				(justify left bottom)
				(hide yes)
			)
		)
		(property "Datasheet" "https://www.ti.com/lit/ds/symlink/sn75dp159.pdf?ts=1728245191743&ref_url=https%253A%252F%252Fwww.mouser.de%252F"
			(at 132.08 166.37 0)
			(effects
				(font
					(size 1.27 1.27)
					(thickness 0.15)
				)
				(justify left bottom)
				(hide yes)
			)
		)
		(property "Description" ""
			(at 81.28 156.21 0)
			(effects
				(font
					(size 1.27 1.27)
				)
				(hide yes)
			)
		)
		(property "MPN" "SN65DP159RGZR "
			(at 95.25 151.13 0)
			(effects
				(font
					(size 1.27 1.27)
					(thickness 0.15)
				)
			)
		)
		(property "Manufacturer" "Texas Instruments"
			(at 132.08 168.91 0)
			(effects
				(font
					(size 1.27 1.27)
					(thickness 0.15)
				)
				(justify left bottom)
				(hide yes)
			)
		)
		(property "Author" "Antmicro"
			(at 132.08 171.45 0)
			(effects
				(font
					(size 1.27 1.27)
					(thickness 0.15)
				)
				(justify left bottom)
				(hide yes)
			)
		)
		(property "License" "Apache-2.0"
			(at 132.08 173.99 0)
			(effects
				(font
					(size 1.27 1.27)
					(thickness 0.15)
				)
				(justify left bottom)
				(hide yes)
			)
		)
		(pin "14"
		)
		(pin "29"
		)
		(pin "11"
		)
		(pin "47"
		)
		(pin "26"
		)
		(pin "25"
		)
		(pin "34"
		)
		(pin "48"
		)
		(pin "24"
		)
		(pin "45"
		)
		(pin "46"
		)
		(pin "44"
		)
		(pin "39"
		)
		(pin "32"
		)
		(pin "38"
		)
		(pin "28"
		)
		(pin "43"
		)
		(pin "12"
		)
		(pin "40"
		)
		(pin "8"
		)
		(pin "36"
		)
		(pin "23"
		)
		(pin "9"
		)
		(pin "41"
		)
		(pin "37"
		)
		(pin "7"
		)
		(pin "6"
		)
		(pin "49"
		)
		(pin "30"
		)
		(pin "35"
		)
		(pin "5"
		)
		(pin "42"
		)
		(pin "20"
		)
		(pin "31"
		)
		(pin "27"
		)
		(pin "3"
		)
		(pin "21"
		)
		(pin "1"
		)
		(pin "33"
		)
		(pin "18"
		)
		(pin "13"
		)
		(pin "15"
		)
		(pin "10"
		)
		(pin "19"
		)
		(pin "2"
		)
		(pin "22"
		)
		(pin "17"
		)
		(pin "16"
		)
		(pin "4"
		)
		(instances
			(project "data-center-rdimm-ddr5-tester"
				(path ""
					(reference "U38")
					(unit 1)
				)
			)
		)
	)
	(symbol
		(lib_id "antmicroTVSDiodes:TPD4E05U06QDQARQ1")
		(at 341.63 194.31 0)
		(unit 1)
		(exclude_from_sim no)
		(in_bom yes)
		(on_board yes)
		(dnp no)
		(fields_autoplaced yes)
		(property "Reference" "U41"
			(at 344.17 190.5 0)
			(effects
				(font
					(size 1.27 1.27)
				)
				(justify left)
			)
		)
		(property "Value" "TPD4E05U06QDQARQ1"
			(at 344.17 207.645 0)
			(effects
				(font
					(size 1.27 1.27)
					(thickness 0.15)
				)
				(justify left)
				(hide yes)
			)
		)
		(property "Footprint" "antmicro-footprints:USON-10_2.5x1mm_P0.5mm"
			(at 365.76 199.39 0)
			(effects
				(font
					(size 1.27 1.27)
					(thickness 0.15)
				)
				(justify left bottom)
				(hide yes)
			)
		)
		(property "Datasheet" "https://www.ti.com/lit/ds/symlink/tpd4e05u06-q1.pdf?HQS=dis-mous-null-mousermode-dsf-pf-null-wwe&ts=1663591265741&ref_url=https%253A%252F%252Fwww.mouser.com%252F"
			(at 365.76 201.93 0)
			(effects
				(font
					(size 1.27 1.27)
					(thickness 0.15)
				)
				(justify left bottom)
				(hide yes)
			)
		)
		(property "Description" ""
			(at 341.63 194.31 0)
			(effects
				(font
					(size 1.27 1.27)
				)
				(hide yes)
			)
		)
		(property "Manufacturer" "Texas Instruments"
			(at 365.76 204.47 0)
			(effects
				(font
					(size 1.27 1.27)
					(thickness 0.15)
				)
				(justify left bottom)
				(hide yes)
			)
		)
		(property "MPN" "TPD4E05U06QDQARQ1"
			(at 340.995 207.645 0)
			(effects
				(font
					(size 1.27 1.27)
					(thickness 0.15)
				)
				(justify left)
			)
		)
		(property "Author" "Antmicro"
			(at 365.76 209.55 0)
			(effects
				(font
					(size 1.27 1.27)
					(thickness 0.15)
				)
				(justify left bottom)
				(hide yes)
			)
		)
		(property "License" "Apache-2.0"
			(at 365.76 212.09 0)
			(effects
				(font
					(size 1.27 1.27)
					(thickness 0.15)
				)
				(justify left bottom)
				(hide yes)
			)
		)
		(pin "1"
		)
		(pin "10"
		)
		(pin "2"
		)
		(pin "3"
		)
		(pin "4"
		)
		(pin "5"
		)
		(pin "6"
		)
		(pin "7"
		)
		(pin "8"
		)
		(pin "9"
		)
		(instances
			(project "data-center-rdimm-ddr5-tester"
				(path ""
					(reference "U41")
					(unit 1)
				)
			)
		)
	)
	(symbol
		(lib_id "antmicroFixedInductors:L_20n_0.35A_0402")
		(at 336.55 45.72 90)
		(unit 1)
		(exclude_from_sim no)
		(in_bom yes)
		(on_board yes)
		(dnp no)
		(property "Reference" "L8"
			(at 337.82 41.91 90)
			(effects
				(font
					(size 1.27 1.27)
					(thickness 0.15)
				)
				(justify right)
			)
		)
		(property "Value" "L_20n_0.35A_0402"
			(at 339.09 31.75 0)
			(effects
				(font
					(size 1.27 1.27)
					(thickness 0.15)
				)
				(justify left bottom)
				(hide yes)
			)
		)
		(property "Footprint" "antmicro-footprints:L_0402_1005Metric"
			(at 344.17 31.75 0)
			(effects
				(font
					(size 1.27 1.27)
					(thickness 0.15)
				)
				(justify left bottom)
				(hide yes)
			)
		)
		(property "Datasheet" "https://product.tdk.com/system/files/dam/doc/product/inductor/inductor/smd/catalog/inductor_automotive_high-frequency_mlg1005s_en.pdf?ref_disty=mouser"
			(at 346.71 31.75 0)
			(effects
				(font
					(size 1.27 1.27)
					(thickness 0.15)
				)
				(justify left bottom)
				(hide yes)
			)
		)
		(property "Description" ""
			(at 336.55 45.72 0)
			(effects
				(font
					(size 1.27 1.27)
				)
				(hide yes)
			)
		)
		(property "Val" "20n/0.35A"
			(at 334.01 40.005 0)
			(effects
				(font
					(size 1.27 1.27)
					(thickness 0.15)
				)
				(justify right)
			)
		)
		(property "Manufacturer" "TDK"
			(at 349.25 31.75 0)
			(effects
				(font
					(size 1.27 1.27)
					(thickness 0.15)
				)
				(justify left bottom)
				(hide yes)
			)
		)
		(property "MPN" "MLG1005S20NJTD25"
			(at 351.79 31.75 0)
			(effects
				(font
					(size 1.27 1.27)
					(thickness 0.15)
				)
				(justify left bottom)
				(hide yes)
			)
		)
		(property "ISat" ""
			(at 353.06 31.75 0)
			(effects
				(font
					(size 1.27 1.27)
				)
				(justify left)
				(hide yes)
			)
		)
		(property "IMax" "0.35 A"
			(at 356.87 31.75 0)
			(effects
				(font
					(size 1.27 1.27)
					(thickness 0.15)
				)
				(justify left bottom)
				(hide yes)
			)
		)
		(property "Size" "1.0x0.5"
			(at 359.41 31.75 0)
			(effects
				(font
					(size 1.27 1.27)
					(thickness 0.15)
				)
				(justify left bottom)
				(hide yes)
			)
		)
		(property "Author" "Antmicro"
			(at 361.95 31.75 0)
			(effects
				(font
					(size 1.27 1.27)
					(thickness 0.15)
				)
				(justify left bottom)
				(hide yes)
			)
		)
		(property "License" "Apache-2.0"
			(at 364.49 31.75 0)
			(effects
				(font
					(size 1.27 1.27)
					(thickness 0.15)
				)
				(justify left bottom)
				(hide yes)
			)
		)
		(pin "2"
		)
		(pin "1"
		)
		(instances
			(project "data-center-rdimm-ddr5-tester"
				(path ""
					(reference "L8")
					(unit 1)
				)
			)
		)
	)
	(symbol
		(lib_id "antmicroCapacitors0402:C_100n_0402")
		(at 114.3 115.57 90)
		(unit 1)
		(exclude_from_sim no)
		(in_bom yes)
		(on_board yes)
		(dnp no)
		(fields_autoplaced yes)
		(property "Reference" "C295"
			(at 118.11 111.7536 90)
			(effects
				(font
					(size 1.27 1.27)
					(thickness 0.15)
				)
				(justify right)
			)
		)
		(property "Value" "C_100n_0402"
			(at 124.46 95.25 0)
			(effects
				(font
					(size 1.27 1.27)
					(thickness 0.15)
				)
				(justify left bottom)
				(hide yes)
			)
		)
		(property "Footprint" "antmicro-footprints:C_0402_1005Metric"
			(at 127 95.25 0)
			(effects
				(font
					(size 1.27 1.27)
					(thickness 0.15)
				)
				(justify left bottom)
				(hide yes)
			)
		)
		(property "Datasheet" "https://www.murata.com/products/productdetail?partno=GRM155R61H104KE14%23"
			(at 129.54 95.25 0)
			(effects
				(font
					(size 1.27 1.27)
					(thickness 0.15)
				)
				(justify left bottom)
				(hide yes)
			)
		)
		(property "Description" ""
			(at 114.3 115.57 0)
			(effects
				(font
					(size 1.27 1.27)
				)
				(hide yes)
			)
		)
		(property "MPN" "GRM155R61H104KE14D"
			(at 132.08 95.25 0)
			(effects
				(font
					(size 1.27 1.27)
					(thickness 0.15)
				)
				(justify left bottom)
				(hide yes)
			)
		)
		(property "Manufacturer" "Murata"
			(at 134.62 95.25 0)
			(effects
				(font
					(size 1.27 1.27)
					(thickness 0.15)
				)
				(justify left bottom)
				(hide yes)
			)
		)
		(property "License" "Apache-2.0"
			(at 137.16 95.25 0)
			(effects
				(font
					(size 1.27 1.27)
					(thickness 0.15)
				)
				(justify left bottom)
				(hide yes)
			)
		)
		(property "Author" "Antmicro"
			(at 139.7 95.25 0)
			(effects
				(font
					(size 1.27 1.27)
					(thickness 0.15)
				)
				(justify left bottom)
				(hide yes)
			)
		)
		(property "Val" "100n"
			(at 118.11 114.2936 90)
			(effects
				(font
					(size 1.27 1.27)
					(thickness 0.15)
				)
				(justify right)
			)
		)
		(property "Voltage" "50V"
			(at 142.24 95.25 0)
			(effects
				(font
					(size 1.27 1.27)
				)
				(justify left bottom)
				(hide yes)
			)
		)
		(property "Dielectric" "X5R"
			(at 144.78 95.25 0)
			(effects
				(font
					(size 1.27 1.27)
				)
				(justify left bottom)
				(hide yes)
			)
		)
		(pin "1"
		)
		(pin "2"
		)
		(instances
			(project "data-center-rdimm-ddr5-tester"
				(path ""
					(reference "C295")
					(unit 1)
				)
			)
		)
	)
	(symbol
		(lib_id "antmicropower:GND")
		(at 354.33 133.35 0)
		(unit 1)
		(exclude_from_sim no)
		(in_bom yes)
		(on_board yes)
		(dnp no)
		(fields_autoplaced yes)
		(property "Reference" "#PWR0473"
			(at 354.33 139.7 0)
			(effects
				(font
					(size 1.27 1.27)
				)
				(hide yes)
			)
		)
		(property "Value" "GND"
			(at 352.425 137.795 0)
			(effects
				(font
					(size 1.27 1.27)
					(thickness 0.15)
				)
				(justify left bottom)
			)
		)
		(property "Footprint" ""
			(at 363.22 140.97 0)
			(effects
				(font
					(size 1.27 1.27)
					(thickness 0.15)
				)
				(justify left bottom)
				(hide yes)
			)
		)
		(property "Datasheet" ""
			(at 363.22 146.05 0)
			(effects
				(font
					(size 1.27 1.27)
					(thickness 0.15)
				)
				(justify left bottom)
				(hide yes)
			)
		)
		(property "Description" ""
			(at 354.33 133.35 0)
			(effects
				(font
					(size 1.27 1.27)
				)
				(hide yes)
			)
		)
		(property "Author" "Antmicro"
			(at 363.22 138.43 0)
			(effects
				(font
					(size 1.27 1.27)
					(thickness 0.15)
				)
				(justify left bottom)
				(hide yes)
			)
		)
		(property "License" "Apache-2.0"
			(at 363.22 140.97 0)
			(effects
				(font
					(size 1.27 1.27)
					(thickness 0.15)
				)
				(justify left bottom)
				(hide yes)
			)
		)
		(pin "1"
		)
		(instances
			(project "data-center-rdimm-ddr5-tester"
				(path ""
					(reference "#PWR0473")
					(unit 1)
				)
			)
		)
	)
	(symbol
		(lib_id "antmicroResistors0402:R_64k9_0402")
		(at 39.37 261.62 180)
		(unit 1)
		(exclude_from_sim no)
		(in_bom no)
		(on_board yes)
		(dnp yes)
		(property "Reference" "R224"
			(at 39.37 260.35 0)
			(effects
				(font
					(size 1.27 1.27)
					(thickness 0.15)
				)
				(justify right)
			)
		)
		(property "Value" "R_64k9_0402"
			(at 19.05 248.92 0)
			(effects
				(font
					(size 1.27 1.27)
					(thickness 0.15)
				)
				(justify left bottom)
				(hide yes)
			)
		)
		(property "Footprint" "antmicro-footprints:R_0402_1005Metric"
			(at 19.05 246.38 0)
			(effects
				(font
					(size 1.27 1.27)
					(thickness 0.15)
				)
				(justify left bottom)
				(hide yes)
			)
		)
		(property "Datasheet" "https://www.bourns.com/docs/product-datasheets/cr.pdf"
			(at 19.05 243.84 0)
			(effects
				(font
					(size 1.27 1.27)
					(thickness 0.15)
				)
				(justify left bottom)
				(hide yes)
			)
		)
		(property "Description" ""
			(at 39.37 261.62 0)
			(effects
				(font
					(size 1.27 1.27)
				)
				(hide yes)
			)
		)
		(property "MPN" "CR0402-FX-6492GLF"
			(at 19.05 241.3 0)
			(effects
				(font
					(size 1.27 1.27)
					(thickness 0.15)
				)
				(justify left bottom)
				(hide yes)
			)
		)
		(property "Manufacturer" "Bourns"
			(at 19.05 238.76 0)
			(effects
				(font
					(size 1.27 1.27)
					(thickness 0.15)
				)
				(justify left bottom)
				(hide yes)
			)
		)
		(property "License" "Apache-2.0"
			(at 19.05 236.22 0)
			(effects
				(font
					(size 1.27 1.27)
					(thickness 0.15)
				)
				(justify left bottom)
				(hide yes)
			)
		)
		(property "Author" "Antmicro"
			(at 19.05 233.68 0)
			(effects
				(font
					(size 1.27 1.27)
					(thickness 0.15)
				)
				(justify left bottom)
				(hide yes)
			)
		)
		(property "Val" "64k9"
			(at 29.21 260.35 0)
			(effects
				(font
					(size 1.27 1.27)
					(thickness 0.15)
				)
				(justify right)
			)
		)
		(property "Tolerance" "1%"
			(at 19.05 251.46 0)
			(effects
				(font
					(size 1.27 1.27)
				)
				(justify left bottom)
				(hide yes)
			)
		)
		(pin "2"
		)
		(pin "1"
		)
		(instances
			(project "data-center-rdimm-ddr5-tester"
				(path ""
					(reference "R224")
					(unit 1)
				)
			)
		)
	)
	(symbol
		(lib_id "antmicroResistors0402:R_10k_0402")
		(at 55.88 77.47 90)
		(unit 1)
		(exclude_from_sim no)
		(in_bom yes)
		(on_board yes)
		(dnp no)
		(fields_autoplaced yes)
		(property "Reference" "R23"
			(at 58.42 73.66 90)
			(effects
				(font
					(size 1.27 1.27)
					(thickness 0.15)
				)
				(justify right)
			)
		)
		(property "Value" "R_10k_0402"
			(at 68.58 57.15 0)
			(effects
				(font
					(size 1.27 1.27)
					(thickness 0.15)
				)
				(justify left bottom)
				(hide yes)
			)
		)
		(property "Footprint" "antmicro-footprints:R_0402_1005Metric"
			(at 71.12 57.15 0)
			(effects
				(font
					(size 1.27 1.27)
					(thickness 0.15)
				)
				(justify left bottom)
				(hide yes)
			)
		)
		(property "Datasheet" "https://www.bourns.com/docs/product-datasheets/cr.pdf"
			(at 73.66 57.15 0)
			(effects
				(font
					(size 1.27 1.27)
					(thickness 0.15)
				)
				(justify left bottom)
				(hide yes)
			)
		)
		(property "Description" ""
			(at 55.88 77.47 0)
			(effects
				(font
					(size 1.27 1.27)
				)
				(hide yes)
			)
		)
		(property "MPN" "CR0402-FX-1002GLF"
			(at 76.2 57.15 0)
			(effects
				(font
					(size 1.27 1.27)
					(thickness 0.15)
				)
				(justify left bottom)
				(hide yes)
			)
		)
		(property "Manufacturer" "Bourns"
			(at 78.74 57.15 0)
			(effects
				(font
					(size 1.27 1.27)
					(thickness 0.15)
				)
				(justify left bottom)
				(hide yes)
			)
		)
		(property "License" "Apache-2.0"
			(at 81.28 57.15 0)
			(effects
				(font
					(size 1.27 1.27)
					(thickness 0.15)
				)
				(justify left bottom)
				(hide yes)
			)
		)
		(property "Author" "Antmicro"
			(at 83.82 57.15 0)
			(effects
				(font
					(size 1.27 1.27)
					(thickness 0.15)
				)
				(justify left bottom)
				(hide yes)
			)
		)
		(property "Val" "10k"
			(at 58.42 76.2 90)
			(effects
				(font
					(size 1.27 1.27)
					(thickness 0.15)
				)
				(justify right)
			)
		)
		(property "Tolerance" "1%"
			(at 66.04 57.15 0)
			(effects
				(font
					(size 1.27 1.27)
				)
				(justify left bottom)
				(hide yes)
			)
		)
		(pin "2"
		)
		(pin "1"
		)
		(instances
			(project "data-center-rdimm-ddr5-tester"
				(path ""
					(reference "R23")
					(unit 1)
				)
			)
		)
	)
	(symbol
		(lib_id "antmicroMemory:M24C64-F_DFN8")
		(at 222.25 264.16 0)
		(unit 1)
		(exclude_from_sim no)
		(in_bom yes)
		(on_board yes)
		(dnp no)
		(fields_autoplaced yes)
		(property "Reference" "U42"
			(at 229.87 256.54 0)
			(effects
				(font
					(size 1.27 1.27)
					(thickness 0.15)
				)
			)
		)
		(property "Value" "M24C64-F_DFN8"
			(at 260.35 279.4 0)
			(effects
				(font
					(size 1.27 1.27)
					(thickness 0.15)
				)
				(justify left bottom)
				(hide yes)
			)
		)
		(property "Footprint" "antmicro-footprints:DFN-8-1EP_3x2mm_P0.5mm_EP1.36x1.46mm"
			(at 260.35 271.78 0)
			(effects
				(font
					(size 1.27 1.27)
					(thickness 0.15)
				)
				(justify left bottom)
				(hide yes)
			)
		)
		(property "Datasheet" "https://eu.mouser.com/datasheet/2/389/cd00259166-1797197.pdf"
			(at 260.35 274.32 0)
			(effects
				(font
					(size 1.27 1.27)
					(thickness 0.15)
				)
				(justify left bottom)
				(hide yes)
			)
		)
		(property "Description" ""
			(at 222.25 264.16 0)
			(effects
				(font
					(size 1.27 1.27)
				)
				(hide yes)
			)
		)
		(property "Manufacturer" "STMicroelectronics"
			(at 260.35 276.86 0)
			(effects
				(font
					(size 1.27 1.27)
					(thickness 0.15)
				)
				(justify left bottom)
				(hide yes)
			)
		)
		(property "MPN" "M24C64-FMC6TG"
			(at 229.87 259.08 0)
			(effects
				(font
					(size 1.27 1.27)
					(thickness 0.15)
				)
			)
		)
		(property "Author" "Antmicro"
			(at 260.35 281.94 0)
			(effects
				(font
					(size 1.27 1.27)
					(thickness 0.15)
				)
				(justify left bottom)
				(hide yes)
			)
		)
		(property "License" "Apache-2.0"
			(at 260.35 284.48 0)
			(effects
				(font
					(size 1.27 1.27)
					(thickness 0.15)
				)
				(justify left bottom)
				(hide yes)
			)
		)
		(pin "6"
		)
		(pin "4"
		)
		(pin "5"
		)
		(pin "1"
		)
		(pin "9"
		)
		(pin "7"
		)
		(pin "8"
		)
		(pin "3"
		)
		(pin "2"
		)
		(instances
			(project "data-center-rdimm-ddr5-tester"
				(path ""
					(reference "U42")
					(unit 1)
				)
			)
		)
	)
	(symbol
		(lib_id "antmicropower:GND")
		(at 220.98 276.86 0)
		(unit 1)
		(exclude_from_sim no)
		(in_bom yes)
		(on_board yes)
		(dnp no)
		(property "Reference" "#PWR0144"
			(at 229.87 279.4 0)
			(effects
				(font
					(size 1.27 1.27)
					(thickness 0.15)
				)
				(justify left bottom)
				(hide yes)
			)
		)
		(property "Value" "GND"
			(at 220.98 280.67 0)
			(effects
				(font
					(size 1.27 1.27)
					(thickness 0.15)
				)
			)
		)
		(property "Footprint" ""
			(at 229.87 284.48 0)
			(effects
				(font
					(size 1.27 1.27)
					(thickness 0.15)
				)
				(justify left bottom)
				(hide yes)
			)
		)
		(property "Datasheet" ""
			(at 229.87 289.56 0)
			(effects
				(font
					(size 1.27 1.27)
					(thickness 0.15)
				)
				(justify left bottom)
				(hide yes)
			)
		)
		(property "Description" ""
			(at 220.98 276.86 0)
			(effects
				(font
					(size 1.27 1.27)
				)
				(hide yes)
			)
		)
		(property "Author" "Antmicro"
			(at 229.87 284.48 0)
			(effects
				(font
					(size 1.27 1.27)
					(thickness 0.15)
				)
				(justify left bottom)
				(hide yes)
			)
		)
		(property "License" "Apache-2.0"
			(at 229.87 287.02 0)
			(effects
				(font
					(size 1.27 1.27)
					(thickness 0.15)
				)
				(justify left bottom)
				(hide yes)
			)
		)
		(pin "1"
		)
		(instances
			(project "data-center-rdimm-ddr5-tester"
				(path ""
					(reference "#PWR0144")
					(unit 1)
				)
			)
		)
	)
	(symbol
		(lib_id "antmicroCapacitors0402:C_100n_0402")
		(at 168.91 264.16 270)
		(unit 1)
		(exclude_from_sim no)
		(in_bom yes)
		(on_board yes)
		(dnp no)
		(property "Reference" "C283"
			(at 167.64 270.51 0)
			(effects
				(font
					(size 1.27 1.27)
					(thickness 0.15)
				)
			)
		)
		(property "Value" "C_100n_0402"
			(at 158.75 284.48 0)
			(effects
				(font
					(size 1.27 1.27)
					(thickness 0.15)
				)
				(justify left bottom)
				(hide yes)
			)
		)
		(property "Footprint" "antmicro-footprints:C_0402_1005Metric"
			(at 156.21 284.48 0)
			(effects
				(font
					(size 1.27 1.27)
					(thickness 0.15)
				)
				(justify left bottom)
				(hide yes)
			)
		)
		(property "Datasheet" "https://www.murata.com/products/productdetail?partno=GRM155R61H104KE14%23"
			(at 153.67 284.48 0)
			(effects
				(font
					(size 1.27 1.27)
					(thickness 0.15)
				)
				(justify left bottom)
				(hide yes)
			)
		)
		(property "Description" ""
			(at 168.91 264.16 0)
			(effects
				(font
					(size 1.27 1.27)
				)
				(hide yes)
			)
		)
		(property "MPN" "GRM155R61H104KE14D"
			(at 151.13 284.48 0)
			(effects
				(font
					(size 1.27 1.27)
					(thickness 0.15)
				)
				(justify left bottom)
				(hide yes)
			)
		)
		(property "Manufacturer" "Murata"
			(at 148.59 284.48 0)
			(effects
				(font
					(size 1.27 1.27)
					(thickness 0.15)
				)
				(justify left bottom)
				(hide yes)
			)
		)
		(property "License" "Apache-2.0"
			(at 146.05 284.48 0)
			(effects
				(font
					(size 1.27 1.27)
					(thickness 0.15)
				)
				(justify left bottom)
				(hide yes)
			)
		)
		(property "Author" "Antmicro"
			(at 143.51 284.48 0)
			(effects
				(font
					(size 1.27 1.27)
					(thickness 0.15)
				)
				(justify left bottom)
				(hide yes)
			)
		)
		(property "Val" "100n"
			(at 166.37 260.35 0)
			(effects
				(font
					(size 1.27 1.27)
					(thickness 0.15)
				)
				(justify left bottom)
			)
		)
		(property "Voltage" "50V"
			(at 140.97 284.48 0)
			(effects
				(font
					(size 1.27 1.27)
				)
				(justify left bottom)
				(hide yes)
			)
		)
		(property "Dielectric" "X5R"
			(at 138.43 284.48 0)
			(effects
				(font
					(size 1.27 1.27)
				)
				(justify left bottom)
				(hide yes)
			)
		)
		(property "Public" ""
			(at 135.89 284.48 0)
			(effects
				(font
					(size 1.27 1.27)
				)
				(justify left bottom)
				(hide yes)
			)
		)
		(pin "2"
		)
		(pin "1"
		)
		(instances
			(project "data-center-rdimm-ddr5-tester"
				(path ""
					(reference "C283")
					(unit 1)
				)
			)
		)
	)
	(symbol
		(lib_id "antmicroResistors0402:R_64k9_0402")
		(at 71.12 261.62 180)
		(unit 1)
		(exclude_from_sim no)
		(in_bom no)
		(on_board yes)
		(dnp yes)
		(property "Reference" "R71"
			(at 71.12 260.35 0)
			(effects
				(font
					(size 1.27 1.27)
					(thickness 0.15)
				)
				(justify right)
			)
		)
		(property "Value" "R_64k9_0402"
			(at 50.8 248.92 0)
			(effects
				(font
					(size 1.27 1.27)
					(thickness 0.15)
				)
				(justify left bottom)
				(hide yes)
			)
		)
		(property "Footprint" "antmicro-footprints:R_0402_1005Metric"
			(at 50.8 246.38 0)
			(effects
				(font
					(size 1.27 1.27)
					(thickness 0.15)
				)
				(justify left bottom)
				(hide yes)
			)
		)
		(property "Datasheet" "https://www.bourns.com/docs/product-datasheets/cr.pdf"
			(at 50.8 243.84 0)
			(effects
				(font
					(size 1.27 1.27)
					(thickness 0.15)
				)
				(justify left bottom)
				(hide yes)
			)
		)
		(property "Description" ""
			(at 71.12 261.62 0)
			(effects
				(font
					(size 1.27 1.27)
				)
				(hide yes)
			)
		)
		(property "MPN" "CR0402-FX-6492GLF"
			(at 50.8 241.3 0)
			(effects
				(font
					(size 1.27 1.27)
					(thickness 0.15)
				)
				(justify left bottom)
				(hide yes)
			)
		)
		(property "Manufacturer" "Bourns"
			(at 50.8 238.76 0)
			(effects
				(font
					(size 1.27 1.27)
					(thickness 0.15)
				)
				(justify left bottom)
				(hide yes)
			)
		)
		(property "License" "Apache-2.0"
			(at 50.8 236.22 0)
			(effects
				(font
					(size 1.27 1.27)
					(thickness 0.15)
				)
				(justify left bottom)
				(hide yes)
			)
		)
		(property "Author" "Antmicro"
			(at 50.8 233.68 0)
			(effects
				(font
					(size 1.27 1.27)
					(thickness 0.15)
				)
				(justify left bottom)
				(hide yes)
			)
		)
		(property "Val" "64k9"
			(at 60.96 260.35 0)
			(effects
				(font
					(size 1.27 1.27)
					(thickness 0.15)
				)
				(justify right)
			)
		)
		(property "Tolerance" "1%"
			(at 50.8 251.46 0)
			(effects
				(font
					(size 1.27 1.27)
				)
				(justify left bottom)
				(hide yes)
			)
		)
		(pin "2"
		)
		(pin "1"
		)
		(instances
			(project "data-center-rdimm-ddr5-tester"
				(path ""
					(reference "R71")
					(unit 1)
				)
			)
		)
	)
	(symbol
		(lib_id "antmicropower:+1V8")
		(at 55.88 71.12 0)
		(unit 1)
		(exclude_from_sim no)
		(in_bom yes)
		(on_board yes)
		(dnp no)
		(fields_autoplaced yes)
		(property "Reference" "#PWR0484"
			(at 71.12 73.66 0)
			(effects
				(font
					(size 1.27 1.27)
					(thickness 0.15)
				)
				(justify left bottom)
				(hide yes)
			)
		)
		(property "Value" "+1V8"
			(at 55.88 67.31 0)
			(effects
				(font
					(size 1.27 1.27)
					(thickness 0.15)
				)
			)
		)
		(property "Footprint" ""
			(at 71.12 78.74 0)
			(effects
				(font
					(size 1.27 1.27)
					(thickness 0.15)
				)
				(justify left bottom)
				(hide yes)
			)
		)
		(property "Datasheet" ""
			(at 71.12 81.28 0)
			(effects
				(font
					(size 1.27 1.27)
					(thickness 0.15)
				)
				(justify left bottom)
				(hide yes)
			)
		)
		(property "Description" ""
			(at 55.88 71.12 0)
			(effects
				(font
					(size 1.27 1.27)
				)
				(hide yes)
			)
		)
		(property "Author" "Antmicro"
			(at 71.12 76.2 0)
			(effects
				(font
					(size 1.27 1.27)
					(thickness 0.15)
				)
				(justify left bottom)
				(hide yes)
			)
		)
		(property "License" "Apache-2.0"
			(at 71.12 78.74 0)
			(effects
				(font
					(size 1.27 1.27)
					(thickness 0.15)
				)
				(justify left bottom)
				(hide yes)
			)
		)
		(pin "1"
		)
		(instances
			(project "data-center-rdimm-ddr5-tester"
				(path ""
					(reference "#PWR0484")
					(unit 1)
				)
			)
		)
	)
	(symbol
		(lib_id "antmicroResistors0402:R_49k9_0402")
		(at 345.44 38.1 90)
		(unit 1)
		(exclude_from_sim no)
		(in_bom yes)
		(on_board yes)
		(dnp no)
		(fields_autoplaced yes)
		(property "Reference" "R33"
			(at 347.345 34.29 90)
			(effects
				(font
					(size 1.27 1.27)
					(thickness 0.15)
				)
				(justify right)
			)
		)
		(property "Value" "R_49k9_0402"
			(at 358.14 17.78 0)
			(effects
				(font
					(size 1.27 1.27)
					(thickness 0.15)
				)
				(justify left bottom)
				(hide yes)
			)
		)
		(property "Footprint" "antmicro-footprints:R_0402_1005Metric"
			(at 360.68 17.78 0)
			(effects
				(font
					(size 1.27 1.27)
					(thickness 0.15)
				)
				(justify left bottom)
				(hide yes)
			)
		)
		(property "Datasheet" "https://www.bourns.com/docs/product-datasheets/cr.pdf"
			(at 363.22 17.78 0)
			(effects
				(font
					(size 1.27 1.27)
					(thickness 0.15)
				)
				(justify left bottom)
				(hide yes)
			)
		)
		(property "Description" ""
			(at 345.44 38.1 0)
			(effects
				(font
					(size 1.27 1.27)
				)
				(hide yes)
			)
		)
		(property "MPN" "CR0402-FX-4992GLF"
			(at 365.76 17.78 0)
			(effects
				(font
					(size 1.27 1.27)
					(thickness 0.15)
				)
				(justify left bottom)
				(hide yes)
			)
		)
		(property "Manufacturer" "Bourns"
			(at 368.3 17.78 0)
			(effects
				(font
					(size 1.27 1.27)
					(thickness 0.15)
				)
				(justify left bottom)
				(hide yes)
			)
		)
		(property "License" "Apache-2.0"
			(at 370.84 17.78 0)
			(effects
				(font
					(size 1.27 1.27)
					(thickness 0.15)
				)
				(justify left bottom)
				(hide yes)
			)
		)
		(property "Author" "Antmicro"
			(at 373.38 17.78 0)
			(effects
				(font
					(size 1.27 1.27)
					(thickness 0.15)
				)
				(justify left bottom)
				(hide yes)
			)
		)
		(property "Val" "49k9"
			(at 347.345 36.83 90)
			(effects
				(font
					(size 1.27 1.27)
					(thickness 0.15)
				)
				(justify right)
			)
		)
		(property "Tolerance" "1%"
			(at 355.6 17.78 0)
			(effects
				(font
					(size 1.27 1.27)
				)
				(justify left bottom)
				(hide yes)
			)
		)
		(pin "1"
		)
		(pin "2"
		)
		(instances
			(project "data-center-rdimm-ddr5-tester"
				(path ""
					(reference "R33")
					(unit 1)
				)
			)
		)
	)
	(symbol
		(lib_id "antmicropower:GND")
		(at 307.34 245.11 0)
		(unit 1)
		(exclude_from_sim no)
		(in_bom yes)
		(on_board yes)
		(dnp no)
		(property "Reference" "#PWR0219"
			(at 307.34 251.46 0)
			(effects
				(font
					(size 1.27 1.27)
				)
				(hide yes)
			)
		)
		(property "Value" "GND"
			(at 305.435 249.555 0)
			(effects
				(font
					(size 1.27 1.27)
					(thickness 0.15)
				)
				(justify left bottom)
			)
		)
		(property "Footprint" ""
			(at 316.23 252.73 0)
			(effects
				(font
					(size 1.27 1.27)
					(thickness 0.15)
				)
				(justify left bottom)
				(hide yes)
			)
		)
		(property "Datasheet" ""
			(at 316.23 257.81 0)
			(effects
				(font
					(size 1.27 1.27)
					(thickness 0.15)
				)
				(justify left bottom)
				(hide yes)
			)
		)
		(property "Description" ""
			(at 307.34 245.11 0)
			(effects
				(font
					(size 1.27 1.27)
				)
				(hide yes)
			)
		)
		(property "Author" "Antmicro"
			(at 316.23 250.19 0)
			(effects
				(font
					(size 1.27 1.27)
					(thickness 0.15)
				)
				(justify left bottom)
				(hide yes)
			)
		)
		(property "License" "Apache-2.0"
			(at 316.23 252.73 0)
			(effects
				(font
					(size 1.27 1.27)
					(thickness 0.15)
				)
				(justify left bottom)
				(hide yes)
			)
		)
		(pin "1"
		)
		(instances
			(project "data-center-rdimm-ddr5-tester"
				(path ""
					(reference "#PWR0219")
					(unit 1)
				)
			)
		)
	)
	(symbol
		(lib_id "antmicropower:PWR_FLAG")
		(at 365.76 92.71 0)
		(unit 1)
		(exclude_from_sim no)
		(in_bom yes)
		(on_board yes)
		(dnp no)
		(fields_autoplaced yes)
		(property "Reference" "#FLG019"
			(at 365.76 90.805 0)
			(effects
				(font
					(size 1.27 1.27)
				)
				(hide yes)
			)
		)
		(property "Value" "PWR_FLAG"
			(at 365.76 89.1342 0)
			(effects
				(font
					(size 1.27 1.27)
				)
			)
		)
		(property "Footprint" ""
			(at 365.76 92.71 0)
			(effects
				(font
					(size 1.27 1.27)
				)
				(hide yes)
			)
		)
		(property "Datasheet" ""
			(at 365.76 92.71 0)
			(effects
				(font
					(size 1.27 1.27)
				)
				(hide yes)
			)
		)
		(property "Description" ""
			(at 365.76 92.71 0)
			(effects
				(font
					(size 1.27 1.27)
				)
				(hide yes)
			)
		)
		(pin "1"
		)
		(instances
			(project "data-center-rdimm-ddr5-tester"
				(path ""
					(reference "#FLG019")
					(unit 1)
				)
			)
		)
	)
	(symbol
		(lib_id "antmicropower:GND")
		(at 21.59 115.57 0)
		(unit 1)
		(exclude_from_sim no)
		(in_bom yes)
		(on_board yes)
		(dnp no)
		(fields_autoplaced yes)
		(property "Reference" "#PWR0476"
			(at 30.48 118.11 0)
			(effects
				(font
					(size 1.27 1.27)
					(thickness 0.15)
				)
				(justify left bottom)
				(hide yes)
			)
		)
		(property "Value" "GND"
			(at 21.59 120.015 0)
			(effects
				(font
					(size 1.27 1.27)
					(thickness 0.15)
				)
			)
		)
		(property "Footprint" ""
			(at 30.48 123.19 0)
			(effects
				(font
					(size 1.27 1.27)
					(thickness 0.15)
				)
				(justify left bottom)
				(hide yes)
			)
		)
		(property "Datasheet" ""
			(at 30.48 128.27 0)
			(effects
				(font
					(size 1.27 1.27)
					(thickness 0.15)
				)
				(justify left bottom)
				(hide yes)
			)
		)
		(property "Description" ""
			(at 21.59 115.57 0)
			(effects
				(font
					(size 1.27 1.27)
				)
				(hide yes)
			)
		)
		(property "Author" "Antmicro"
			(at 30.48 123.19 0)
			(effects
				(font
					(size 1.27 1.27)
					(thickness 0.15)
				)
				(justify left bottom)
				(hide yes)
			)
		)
		(property "License" "Apache-2.0"
			(at 30.48 125.73 0)
			(effects
				(font
					(size 1.27 1.27)
					(thickness 0.15)
				)
				(justify left bottom)
				(hide yes)
			)
		)
		(pin "1"
		)
		(instances
			(project "data-center-rdimm-ddr5-tester"
				(path ""
					(reference "#PWR0476")
					(unit 1)
				)
			)
		)
	)
	(symbol
		(lib_id "antmicroResistors0402:R_64k9_0402")
		(at 39.37 274.32 180)
		(unit 1)
		(exclude_from_sim no)
		(in_bom no)
		(on_board yes)
		(dnp yes)
		(property "Reference" "R229"
			(at 39.37 273.05 0)
			(effects
				(font
					(size 1.27 1.27)
					(thickness 0.15)
				)
				(justify right)
			)
		)
		(property "Value" "R_64k9_0402"
			(at 19.05 261.62 0)
			(effects
				(font
					(size 1.27 1.27)
					(thickness 0.15)
				)
				(justify left bottom)
				(hide yes)
			)
		)
		(property "Footprint" "antmicro-footprints:R_0402_1005Metric"
			(at 19.05 259.08 0)
			(effects
				(font
					(size 1.27 1.27)
					(thickness 0.15)
				)
				(justify left bottom)
				(hide yes)
			)
		)
		(property "Datasheet" "https://www.bourns.com/docs/product-datasheets/cr.pdf"
			(at 19.05 256.54 0)
			(effects
				(font
					(size 1.27 1.27)
					(thickness 0.15)
				)
				(justify left bottom)
				(hide yes)
			)
		)
		(property "Description" ""
			(at 39.37 274.32 0)
			(effects
				(font
					(size 1.27 1.27)
				)
				(hide yes)
			)
		)
		(property "MPN" "CR0402-FX-6492GLF"
			(at 19.05 254 0)
			(effects
				(font
					(size 1.27 1.27)
					(thickness 0.15)
				)
				(justify left bottom)
				(hide yes)
			)
		)
		(property "Manufacturer" "Bourns"
			(at 19.05 251.46 0)
			(effects
				(font
					(size 1.27 1.27)
					(thickness 0.15)
				)
				(justify left bottom)
				(hide yes)
			)
		)
		(property "License" "Apache-2.0"
			(at 19.05 248.92 0)
			(effects
				(font
					(size 1.27 1.27)
					(thickness 0.15)
				)
				(justify left bottom)
				(hide yes)
			)
		)
		(property "Author" "Antmicro"
			(at 19.05 246.38 0)
			(effects
				(font
					(size 1.27 1.27)
					(thickness 0.15)
				)
				(justify left bottom)
				(hide yes)
			)
		)
		(property "Val" "64k9"
			(at 29.21 273.05 0)
			(effects
				(font
					(size 1.27 1.27)
					(thickness 0.15)
				)
				(justify right)
			)
		)
		(property "Tolerance" "1%"
			(at 19.05 264.16 0)
			(effects
				(font
					(size 1.27 1.27)
				)
				(justify left bottom)
				(hide yes)
			)
		)
		(pin "2"
		)
		(pin "1"
		)
		(instances
			(project "data-center-rdimm-ddr5-tester"
				(path ""
					(reference "R229")
					(unit 1)
				)
			)
		)
	)
	(symbol
		(lib_id "antmicropower:+3V3")
		(at 242.57 262.89 0)
		(unit 1)
		(exclude_from_sim no)
		(in_bom yes)
		(on_board yes)
		(dnp no)
		(property "Reference" "#PWR0180"
			(at 257.81 262.89 0)
			(effects
				(font
					(size 1.27 1.27)
					(thickness 0.15)
				)
				(justify left bottom)
				(hide yes)
			)
		)
		(property "Value" "+3V3"
			(at 242.57 259.08 0)
			(effects
				(font
					(size 1.27 1.27)
					(thickness 0.15)
				)
			)
		)
		(property "Footprint" ""
			(at 257.81 270.51 0)
			(effects
				(font
					(size 1.27 1.27)
					(thickness 0.15)
				)
				(justify left bottom)
				(hide yes)
			)
		)
		(property "Datasheet" ""
			(at 257.81 273.05 0)
			(effects
				(font
					(size 1.27 1.27)
					(thickness 0.15)
				)
				(justify left bottom)
				(hide yes)
			)
		)
		(property "Description" ""
			(at 242.57 262.89 0)
			(effects
				(font
					(size 1.27 1.27)
				)
				(hide yes)
			)
		)
		(property "Author" "Antmicro"
			(at 257.81 265.43 0)
			(effects
				(font
					(size 1.27 1.27)
					(thickness 0.15)
				)
				(justify left bottom)
				(hide yes)
			)
		)
		(property "License" "Apache-2.0"
			(at 257.81 267.97 0)
			(effects
				(font
					(size 1.27 1.27)
					(thickness 0.15)
				)
				(justify left bottom)
				(hide yes)
			)
		)
		(pin "1"
		)
		(instances
			(project "data-center-rdimm-ddr5-tester"
				(path ""
					(reference "#PWR0180")
					(unit 1)
				)
			)
		)
	)
	(symbol
		(lib_id "antmicroResistors0402:R_2k2_0402")
		(at 144.78 185.42 270)
		(mirror x)
		(unit 1)
		(exclude_from_sim no)
		(in_bom yes)
		(on_board yes)
		(dnp no)
		(property "Reference" "R73"
			(at 146.685 181.61 90)
			(effects
				(font
					(size 1.27 1.27)
					(thickness 0.15)
				)
				(justify left)
			)
		)
		(property "Value" "R_2k2_0402"
			(at 132.08 165.1 0)
			(effects
				(font
					(size 1.27 1.27)
					(thickness 0.15)
				)
				(justify left bottom)
				(hide yes)
			)
		)
		(property "Footprint" "antmicro-footprints:R_0402_1005Metric"
			(at 129.54 165.1 0)
			(effects
				(font
					(size 1.27 1.27)
					(thickness 0.15)
				)
				(justify left bottom)
				(hide yes)
			)
		)
		(property "Datasheet" "https://www.bourns.com/docs/product-datasheets/cr.pdf"
			(at 127 165.1 0)
			(effects
				(font
					(size 1.27 1.27)
					(thickness 0.15)
				)
				(justify left bottom)
				(hide yes)
			)
		)
		(property "Description" ""
			(at 144.78 185.42 0)
			(effects
				(font
					(size 1.27 1.27)
				)
				(hide yes)
			)
		)
		(property "MPN" "CR0402-FX-2201GLF"
			(at 124.46 165.1 0)
			(effects
				(font
					(size 1.27 1.27)
					(thickness 0.15)
				)
				(justify left bottom)
				(hide yes)
			)
		)
		(property "Manufacturer" "Bourns"
			(at 121.92 165.1 0)
			(effects
				(font
					(size 1.27 1.27)
					(thickness 0.15)
				)
				(justify left bottom)
				(hide yes)
			)
		)
		(property "License" "Apache-2.0"
			(at 119.38 165.1 0)
			(effects
				(font
					(size 1.27 1.27)
					(thickness 0.15)
				)
				(justify left bottom)
				(hide yes)
			)
		)
		(property "Author" "Antmicro"
			(at 116.84 165.1 0)
			(effects
				(font
					(size 1.27 1.27)
					(thickness 0.15)
				)
				(justify left bottom)
				(hide yes)
			)
		)
		(property "Val" "2k2"
			(at 146.685 184.15 90)
			(effects
				(font
					(size 1.27 1.27)
					(thickness 0.15)
				)
				(justify left)
			)
		)
		(property "Tolerance" "1%"
			(at 134.62 165.1 0)
			(effects
				(font
					(size 1.27 1.27)
				)
				(justify left bottom)
				(hide yes)
			)
		)
		(property "Public" ""
			(at 114.3 165.1 0)
			(effects
				(font
					(size 1.27 1.27)
				)
				(justify left bottom)
				(hide yes)
			)
		)
		(pin "1"
		)
		(pin "2"
		)
		(instances
			(project "data-center-rdimm-ddr5-tester"
				(path ""
					(reference "R73")
					(unit 1)
				)
			)
		)
	)
	(symbol
		(lib_id "antmicroResistors0402:R_0R_0402")
		(at 129.54 257.81 90)
		(unit 1)
		(exclude_from_sim no)
		(in_bom no)
		(on_board yes)
		(dnp yes)
		(property "Reference" "R247"
			(at 130.81 254 90)
			(effects
				(font
					(size 1.27 1.27)
					(thickness 0.15)
				)
				(justify right)
			)
		)
		(property "Value" "R_0R_0402"
			(at 142.24 237.49 0)
			(effects
				(font
					(size 1.27 1.27)
					(thickness 0.15)
				)
				(justify left bottom)
				(hide yes)
			)
		)
		(property "Footprint" "antmicro-footprints:R_0402_1005Metric"
			(at 144.78 237.49 0)
			(effects
				(font
					(size 1.27 1.27)
					(thickness 0.15)
				)
				(justify left bottom)
				(hide yes)
			)
		)
		(property "Datasheet" "https://industrial.panasonic.com/cdbs/www-data/pdf/RDA0000/AOA0000C301.pdf"
			(at 147.32 237.49 0)
			(effects
				(font
					(size 1.27 1.27)
					(thickness 0.15)
				)
				(justify left bottom)
				(hide yes)
			)
		)
		(property "Description" ""
			(at 129.54 257.81 0)
			(effects
				(font
					(size 1.27 1.27)
				)
				(hide yes)
			)
		)
		(property "MPN" "ERJ2GE0R00X"
			(at 149.86 237.49 0)
			(effects
				(font
					(size 1.27 1.27)
					(thickness 0.15)
				)
				(justify left bottom)
				(hide yes)
			)
		)
		(property "Manufacturer" "Panasonic"
			(at 152.4 237.49 0)
			(effects
				(font
					(size 1.27 1.27)
					(thickness 0.15)
				)
				(justify left bottom)
				(hide yes)
			)
		)
		(property "License" "Apache-2.0"
			(at 154.94 237.49 0)
			(effects
				(font
					(size 1.27 1.27)
					(thickness 0.15)
				)
				(justify left bottom)
				(hide yes)
			)
		)
		(property "Author" "Antmicro"
			(at 157.48 237.49 0)
			(effects
				(font
					(size 1.27 1.27)
					(thickness 0.15)
				)
				(justify left bottom)
				(hide yes)
			)
		)
		(property "Val" "0R"
			(at 130.81 256.54 90)
			(effects
				(font
					(size 1.27 1.27)
					(thickness 0.15)
				)
				(justify right)
			)
		)
		(property "Tolerance" "~"
			(at 139.7 237.49 0)
			(effects
				(font
					(size 1.27 1.27)
				)
				(justify left bottom)
				(hide yes)
			)
		)
		(property "Current" "1A"
			(at 160.02 237.49 0)
			(effects
				(font
					(size 1.27 1.27)
					(thickness 0.15)
				)
				(justify left bottom)
				(hide yes)
			)
		)
		(pin "1"
		)
		(pin "2"
		)
		(instances
			(project "data-center-rdimm-ddr5-tester"
				(path ""
					(reference "R247")
					(unit 1)
				)
			)
		)
	)
	(symbol
		(lib_id "antmicroCapacitors0402:C_1u_0402")
		(at 177.8 54.61 270)
		(unit 1)
		(exclude_from_sim no)
		(in_bom yes)
		(on_board yes)
		(dnp no)
		(fields_autoplaced yes)
		(property "Reference" "C129"
			(at 180.34 55.8863 90)
			(effects
				(font
					(size 1.27 1.27)
				)
				(justify left)
			)
		)
		(property "Value" "C_1u_0402"
			(at 167.64 74.93 0)
			(effects
				(font
					(size 1.27 1.27)
					(thickness 0.15)
				)
				(justify left bottom)
				(hide yes)
			)
		)
		(property "Footprint" "antmicro-footprints:C_0402_1005Metric"
			(at 165.1 74.93 0)
			(effects
				(font
					(size 1.27 1.27)
					(thickness 0.15)
				)
				(justify left bottom)
				(hide yes)
			)
		)
		(property "Datasheet" "https://product.tdk.com/en/search/capacitor/ceramic/mlcc/info?part_no=C1005X6S1A105K050BC"
			(at 162.56 74.93 0)
			(effects
				(font
					(size 1.27 1.27)
					(thickness 0.15)
				)
				(justify left bottom)
				(hide yes)
			)
		)
		(property "Description" ""
			(at 177.8 54.61 0)
			(effects
				(font
					(size 1.27 1.27)
				)
				(hide yes)
			)
		)
		(property "Manufacturer" "TDK"
			(at 157.48 74.93 0)
			(effects
				(font
					(size 1.27 1.27)
					(thickness 0.15)
				)
				(justify left bottom)
				(hide yes)
			)
		)
		(property "MPN" "C1005X6S1A105K050BC"
			(at 160.02 74.93 0)
			(effects
				(font
					(size 1.27 1.27)
					(thickness 0.15)
				)
				(justify left bottom)
				(hide yes)
			)
		)
		(property "Val" "1u"
			(at 180.34 59.0612 90)
			(effects
				(font
					(size 1.27 1.27)
					(thickness 0.15)
				)
				(justify left)
			)
		)
		(property "License" "Apache-2.0"
			(at 154.94 74.93 0)
			(effects
				(font
					(size 1.27 1.27)
					(thickness 0.15)
				)
				(justify left bottom)
				(hide yes)
			)
		)
		(property "Author" "Antmicro"
			(at 152.4 74.93 0)
			(effects
				(font
					(size 1.27 1.27)
					(thickness 0.15)
				)
				(justify left bottom)
				(hide yes)
			)
		)
		(property "Voltage" ""
			(at 149.86 74.93 0)
			(effects
				(font
					(size 1.27 1.27)
				)
				(justify left bottom)
				(hide yes)
			)
		)
		(property "Dielectric" ""
			(at 147.32 74.93 0)
			(effects
				(font
					(size 1.27 1.27)
				)
				(justify left bottom)
				(hide yes)
			)
		)
		(pin "1"
		)
		(pin "2"
		)
		(instances
			(project "data-center-rdimm-ddr5-tester"
				(path ""
					(reference "C129")
					(unit 1)
				)
			)
		)
	)
	(symbol
		(lib_id "antmicroResistors0402:R_49k9_0402")
		(at 336.55 38.1 90)
		(unit 1)
		(exclude_from_sim no)
		(in_bom yes)
		(on_board yes)
		(dnp no)
		(fields_autoplaced yes)
		(property "Reference" "R32"
			(at 338.455 34.29 90)
			(effects
				(font
					(size 1.27 1.27)
					(thickness 0.15)
				)
				(justify right)
			)
		)
		(property "Value" "R_49k9_0402"
			(at 349.25 17.78 0)
			(effects
				(font
					(size 1.27 1.27)
					(thickness 0.15)
				)
				(justify left bottom)
				(hide yes)
			)
		)
		(property "Footprint" "antmicro-footprints:R_0402_1005Metric"
			(at 351.79 17.78 0)
			(effects
				(font
					(size 1.27 1.27)
					(thickness 0.15)
				)
				(justify left bottom)
				(hide yes)
			)
		)
		(property "Datasheet" "https://www.bourns.com/docs/product-datasheets/cr.pdf"
			(at 354.33 17.78 0)
			(effects
				(font
					(size 1.27 1.27)
					(thickness 0.15)
				)
				(justify left bottom)
				(hide yes)
			)
		)
		(property "Description" ""
			(at 336.55 38.1 0)
			(effects
				(font
					(size 1.27 1.27)
				)
				(hide yes)
			)
		)
		(property "MPN" "CR0402-FX-4992GLF"
			(at 356.87 17.78 0)
			(effects
				(font
					(size 1.27 1.27)
					(thickness 0.15)
				)
				(justify left bottom)
				(hide yes)
			)
		)
		(property "Manufacturer" "Bourns"
			(at 359.41 17.78 0)
			(effects
				(font
					(size 1.27 1.27)
					(thickness 0.15)
				)
				(justify left bottom)
				(hide yes)
			)
		)
		(property "License" "Apache-2.0"
			(at 361.95 17.78 0)
			(effects
				(font
					(size 1.27 1.27)
					(thickness 0.15)
				)
				(justify left bottom)
				(hide yes)
			)
		)
		(property "Author" "Antmicro"
			(at 364.49 17.78 0)
			(effects
				(font
					(size 1.27 1.27)
					(thickness 0.15)
				)
				(justify left bottom)
				(hide yes)
			)
		)
		(property "Val" "49k9"
			(at 338.455 36.83 90)
			(effects
				(font
					(size 1.27 1.27)
					(thickness 0.15)
				)
				(justify right)
			)
		)
		(property "Tolerance" "1%"
			(at 346.71 17.78 0)
			(effects
				(font
					(size 1.27 1.27)
				)
				(justify left bottom)
				(hide yes)
			)
		)
		(pin "1"
		)
		(pin "2"
		)
		(instances
			(project "data-center-rdimm-ddr5-tester"
				(path ""
					(reference "R32")
					(unit 1)
				)
			)
		)
	)
	(symbol
		(lib_id "antmicroCapacitors0402:C_10u_6.3V_0402")
		(at 201.93 224.79 90)
		(unit 1)
		(exclude_from_sim no)
		(in_bom yes)
		(on_board yes)
		(dnp no)
		(fields_autoplaced yes)
		(property "Reference" "C126"
			(at 204.2541 221.413 90)
			(effects
				(font
					(size 1.27 1.27)
					(thickness 0.15)
				)
				(justify right)
			)
		)
		(property "Value" "C_10u_6.3V_0402"
			(at 212.09 204.47 0)
			(effects
				(font
					(size 1.27 1.27)
					(thickness 0.15)
				)
				(justify left bottom)
				(hide yes)
			)
		)
		(property "Footprint" "antmicro-footprints:C_0402_1005Metric"
			(at 214.63 204.47 0)
			(effects
				(font
					(size 1.27 1.27)
					(thickness 0.15)
				)
				(justify left bottom)
				(hide yes)
			)
		)
		(property "Datasheet" "https://www.murata.com/products/productdetail?partno=GRM155R60J106ME15%23"
			(at 217.17 204.47 0)
			(effects
				(font
					(size 1.27 1.27)
					(thickness 0.15)
				)
				(justify left bottom)
				(hide yes)
			)
		)
		(property "Description" ""
			(at 201.93 224.79 0)
			(effects
				(font
					(size 1.27 1.27)
				)
				(hide yes)
			)
		)
		(property "MPN" "GRM155R60J106ME15D"
			(at 219.71 204.47 0)
			(effects
				(font
					(size 1.27 1.27)
					(thickness 0.15)
				)
				(justify left bottom)
				(hide yes)
			)
		)
		(property "Manufacturer" "Murata"
			(at 222.25 204.47 0)
			(effects
				(font
					(size 1.27 1.27)
					(thickness 0.15)
				)
				(justify left bottom)
				(hide yes)
			)
		)
		(property "License" "Apache-2.0"
			(at 224.79 204.47 0)
			(effects
				(font
					(size 1.27 1.27)
					(thickness 0.15)
				)
				(justify left bottom)
				(hide yes)
			)
		)
		(property "Author" "Antmicro"
			(at 227.33 204.47 0)
			(effects
				(font
					(size 1.27 1.27)
					(thickness 0.15)
				)
				(justify left bottom)
				(hide yes)
			)
		)
		(property "Val" "10u"
			(at 204.2541 223.9367 90)
			(effects
				(font
					(size 1.27 1.27)
					(thickness 0.15)
				)
				(justify right)
			)
		)
		(property "Voltage" "6.3V"
			(at 229.87 204.47 0)
			(effects
				(font
					(size 1.27 1.27)
				)
				(justify left bottom)
				(hide yes)
			)
		)
		(property "Dielectric" "X5R"
			(at 232.41 204.47 0)
			(effects
				(font
					(size 1.27 1.27)
				)
				(justify left bottom)
				(hide yes)
			)
		)
		(pin "1"
		)
		(pin "2"
		)
		(instances
			(project "data-center-rdimm-ddr5-tester"
				(path ""
					(reference "C126")
					(unit 1)
				)
			)
		)
	)
	(symbol
		(lib_id "antmicroWire2BoardConnectors:I-PEX_CABLINE-VS_1x20_20455-A20E-76")
		(at 391.16 99.06 0)
		(mirror x)
		(unit 1)
		(exclude_from_sim no)
		(in_bom yes)
		(on_board yes)
		(dnp no)
		(property "Reference" "J11"
			(at 393.7 44.45 0)
			(effects
				(font
					(size 1.27 1.27)
					(thickness 0.15)
				)
				(justify left)
			)
		)
		(property "Value" "I-PEX_CABLINE-VS_1x20_20455-A20E-76"
			(at 414.02 91.44 0)
			(effects
				(font
					(size 1.27 1.27)
					(thickness 0.15)
				)
				(justify left bottom)
				(hide yes)
			)
		)
		(property "Footprint" "antmicro-footprints:I-PEX_CABLINE-VS_1x20_20455-A20E-76"
			(at 414.02 88.9 0)
			(effects
				(font
					(size 1.27 1.27)
					(thickness 0.15)
				)
				(justify left bottom)
				(hide yes)
			)
		)
		(property "Datasheet" "https://www.i-pex.com/sites/default/files/downloads/pdf/MANUAL_CABLINE-VS_HIM-08004-07EN.pdf"
			(at 414.02 86.36 0)
			(effects
				(font
					(size 1.27 1.27)
					(thickness 0.15)
				)
				(justify left bottom)
				(hide yes)
			)
		)
		(property "Description" ""
			(at 391.16 99.06 0)
			(effects
				(font
					(size 1.27 1.27)
				)
				(hide yes)
			)
		)
		(property "MPN" "20455-A20E-76"
			(at 391.16 102.87 0)
			(effects
				(font
					(size 1.27 1.27)
					(thickness 0.15)
				)
				(justify left)
			)
		)
		(property "Manufacturer" "I-PEX"
			(at 414.02 83.82 0)
			(effects
				(font
					(size 1.27 1.27)
					(thickness 0.15)
				)
				(justify left bottom)
				(hide yes)
			)
		)
		(property "Author" "Antmicro"
			(at 414.02 81.28 0)
			(effects
				(font
					(size 1.27 1.27)
					(thickness 0.15)
				)
				(justify left bottom)
				(hide yes)
			)
		)
		(property "License" "Apache-2.0"
			(at 414.02 78.74 0)
			(effects
				(font
					(size 1.27 1.27)
					(thickness 0.15)
				)
				(justify left bottom)
				(hide yes)
			)
		)
		(pin "9"
		)
		(pin "17"
		)
		(pin "5"
		)
		(pin "7"
		)
		(pin "19"
		)
		(pin "4"
		)
		(pin "6"
		)
		(pin "SH"
		)
		(pin "20"
		)
		(pin "12"
		)
		(pin "8"
		)
		(pin "13"
		)
		(pin "3"
		)
		(pin "2"
		)
		(pin "16"
		)
		(pin "11"
		)
		(pin "14"
		)
		(pin "18"
		)
		(pin "10"
		)
		(pin "1"
		)
		(pin "15"
		)
		(instances
			(project "data-center-rdimm-ddr5-tester"
				(path ""
					(reference "J11")
					(unit 1)
				)
			)
		)
	)
	(symbol
		(lib_id "antmicropower:GND")
		(at 201.93 226.06 0)
		(unit 1)
		(exclude_from_sim no)
		(in_bom yes)
		(on_board yes)
		(dnp no)
		(property "Reference" "#PWR0209"
			(at 201.93 232.41 0)
			(effects
				(font
					(size 1.27 1.27)
				)
				(hide yes)
			)
		)
		(property "Value" "GND"
			(at 200.025 230.505 0)
			(effects
				(font
					(size 1.27 1.27)
					(thickness 0.15)
				)
				(justify left bottom)
			)
		)
		(property "Footprint" ""
			(at 210.82 233.68 0)
			(effects
				(font
					(size 1.27 1.27)
					(thickness 0.15)
				)
				(justify left bottom)
				(hide yes)
			)
		)
		(property "Datasheet" ""
			(at 210.82 238.76 0)
			(effects
				(font
					(size 1.27 1.27)
					(thickness 0.15)
				)
				(justify left bottom)
				(hide yes)
			)
		)
		(property "Description" ""
			(at 201.93 226.06 0)
			(effects
				(font
					(size 1.27 1.27)
				)
				(hide yes)
			)
		)
		(property "Author" "Antmicro"
			(at 210.82 231.14 0)
			(effects
				(font
					(size 1.27 1.27)
					(thickness 0.15)
				)
				(justify left bottom)
				(hide yes)
			)
		)
		(property "License" "Apache-2.0"
			(at 210.82 233.68 0)
			(effects
				(font
					(size 1.27 1.27)
					(thickness 0.15)
				)
				(justify left bottom)
				(hide yes)
			)
		)
		(pin "1"
		)
		(instances
			(project "data-center-rdimm-ddr5-tester"
				(path ""
					(reference "#PWR0209")
					(unit 1)
				)
			)
		)
	)
	(symbol
		(lib_id "antmicroResistors0402:R_1k_0402")
		(at 311.15 92.71 90)
		(unit 1)
		(exclude_from_sim no)
		(in_bom yes)
		(on_board yes)
		(dnp no)
		(property "Reference" "R82"
			(at 312.42 88.9 90)
			(effects
				(font
					(size 1.27 1.27)
					(thickness 0.15)
				)
				(justify right)
			)
		)
		(property "Value" "R_1k_0402"
			(at 323.85 72.39 0)
			(effects
				(font
					(size 1.27 1.27)
					(thickness 0.15)
				)
				(justify left bottom)
				(hide yes)
			)
		)
		(property "Footprint" "antmicro-footprints:R_0402_1005Metric"
			(at 326.39 72.39 0)
			(effects
				(font
					(size 1.27 1.27)
					(thickness 0.15)
				)
				(justify left bottom)
				(hide yes)
			)
		)
		(property "Datasheet" "https://www.bourns.com/docs/product-datasheets/cr.pdf"
			(at 328.93 72.39 0)
			(effects
				(font
					(size 1.27 1.27)
					(thickness 0.15)
				)
				(justify left bottom)
				(hide yes)
			)
		)
		(property "Description" ""
			(at 311.15 92.71 0)
			(effects
				(font
					(size 1.27 1.27)
				)
				(hide yes)
			)
		)
		(property "MPN" "CR0402-FX-1001GLF"
			(at 331.47 72.39 0)
			(effects
				(font
					(size 1.27 1.27)
					(thickness 0.15)
				)
				(justify left bottom)
				(hide yes)
			)
		)
		(property "Manufacturer" "Bourns"
			(at 334.01 72.39 0)
			(effects
				(font
					(size 1.27 1.27)
					(thickness 0.15)
				)
				(justify left bottom)
				(hide yes)
			)
		)
		(property "License" "Apache-2.0"
			(at 336.55 72.39 0)
			(effects
				(font
					(size 1.27 1.27)
					(thickness 0.15)
				)
				(justify left bottom)
				(hide yes)
			)
		)
		(property "Author" "Antmicro"
			(at 339.09 72.39 0)
			(effects
				(font
					(size 1.27 1.27)
					(thickness 0.15)
				)
				(justify left bottom)
				(hide yes)
			)
		)
		(property "Val" "1k"
			(at 312.42 91.44 90)
			(effects
				(font
					(size 1.27 1.27)
					(thickness 0.15)
				)
				(justify right)
			)
		)
		(property "Tolerance" "1%"
			(at 321.31 72.39 0)
			(effects
				(font
					(size 1.27 1.27)
				)
				(justify left bottom)
				(hide yes)
			)
		)
		(pin "2"
		)
		(pin "1"
		)
		(instances
			(project "data-center-rdimm-ddr5-tester"
				(path ""
					(reference "R82")
					(unit 1)
				)
			)
		)
	)
	(symbol
		(lib_id "antmicroResistors0402:R_49k9_0402")
		(at 370.84 38.1 90)
		(unit 1)
		(exclude_from_sim no)
		(in_bom yes)
		(on_board yes)
		(dnp no)
		(fields_autoplaced yes)
		(property "Reference" "R24"
			(at 372.745 34.29 90)
			(effects
				(font
					(size 1.27 1.27)
					(thickness 0.15)
				)
				(justify right)
			)
		)
		(property "Value" "R_49k9_0402"
			(at 383.54 17.78 0)
			(effects
				(font
					(size 1.27 1.27)
					(thickness 0.15)
				)
				(justify left bottom)
				(hide yes)
			)
		)
		(property "Footprint" "antmicro-footprints:R_0402_1005Metric"
			(at 386.08 17.78 0)
			(effects
				(font
					(size 1.27 1.27)
					(thickness 0.15)
				)
				(justify left bottom)
				(hide yes)
			)
		)
		(property "Datasheet" "https://www.bourns.com/docs/product-datasheets/cr.pdf"
			(at 388.62 17.78 0)
			(effects
				(font
					(size 1.27 1.27)
					(thickness 0.15)
				)
				(justify left bottom)
				(hide yes)
			)
		)
		(property "Description" ""
			(at 370.84 38.1 0)
			(effects
				(font
					(size 1.27 1.27)
				)
				(hide yes)
			)
		)
		(property "MPN" "CR0402-FX-4992GLF"
			(at 391.16 17.78 0)
			(effects
				(font
					(size 1.27 1.27)
					(thickness 0.15)
				)
				(justify left bottom)
				(hide yes)
			)
		)
		(property "Manufacturer" "Bourns"
			(at 393.7 17.78 0)
			(effects
				(font
					(size 1.27 1.27)
					(thickness 0.15)
				)
				(justify left bottom)
				(hide yes)
			)
		)
		(property "License" "Apache-2.0"
			(at 396.24 17.78 0)
			(effects
				(font
					(size 1.27 1.27)
					(thickness 0.15)
				)
				(justify left bottom)
				(hide yes)
			)
		)
		(property "Author" "Antmicro"
			(at 398.78 17.78 0)
			(effects
				(font
					(size 1.27 1.27)
					(thickness 0.15)
				)
				(justify left bottom)
				(hide yes)
			)
		)
		(property "Val" "49k9"
			(at 372.745 36.83 90)
			(effects
				(font
					(size 1.27 1.27)
					(thickness 0.15)
				)
				(justify right)
			)
		)
		(property "Tolerance" "1%"
			(at 381 17.78 0)
			(effects
				(font
					(size 1.27 1.27)
				)
				(justify left bottom)
				(hide yes)
			)
		)
		(pin "1"
		)
		(pin "2"
		)
		(instances
			(project "data-center-rdimm-ddr5-tester"
				(path ""
					(reference "R24")
					(unit 1)
				)
			)
		)
	)
	(symbol
		(lib_id "antmicroFixedInductors:L_20n_0.35A_0402")
		(at 386.08 45.72 90)
		(unit 1)
		(exclude_from_sim no)
		(in_bom yes)
		(on_board yes)
		(dnp no)
		(property "Reference" "L6"
			(at 387.35 41.91 90)
			(effects
				(font
					(size 1.27 1.27)
					(thickness 0.15)
				)
				(justify right)
			)
		)
		(property "Value" "L_20n_0.35A_0402"
			(at 388.62 31.75 0)
			(effects
				(font
					(size 1.27 1.27)
					(thickness 0.15)
				)
				(justify left bottom)
				(hide yes)
			)
		)
		(property "Footprint" "antmicro-footprints:L_0402_1005Metric"
			(at 393.7 31.75 0)
			(effects
				(font
					(size 1.27 1.27)
					(thickness 0.15)
				)
				(justify left bottom)
				(hide yes)
			)
		)
		(property "Datasheet" "https://product.tdk.com/system/files/dam/doc/product/inductor/inductor/smd/catalog/inductor_automotive_high-frequency_mlg1005s_en.pdf?ref_disty=mouser"
			(at 396.24 31.75 0)
			(effects
				(font
					(size 1.27 1.27)
					(thickness 0.15)
				)
				(justify left bottom)
				(hide yes)
			)
		)
		(property "Description" ""
			(at 386.08 45.72 0)
			(effects
				(font
					(size 1.27 1.27)
				)
				(hide yes)
			)
		)
		(property "Val" "20n/0.35A"
			(at 383.54 40.005 0)
			(effects
				(font
					(size 1.27 1.27)
					(thickness 0.15)
				)
				(justify right)
			)
		)
		(property "Manufacturer" "TDK"
			(at 398.78 31.75 0)
			(effects
				(font
					(size 1.27 1.27)
					(thickness 0.15)
				)
				(justify left bottom)
				(hide yes)
			)
		)
		(property "MPN" "MLG1005S20NJTD25"
			(at 401.32 31.75 0)
			(effects
				(font
					(size 1.27 1.27)
					(thickness 0.15)
				)
				(justify left bottom)
				(hide yes)
			)
		)
		(property "ISat" ""
			(at 402.59 31.75 0)
			(effects
				(font
					(size 1.27 1.27)
				)
				(justify left)
				(hide yes)
			)
		)
		(property "IMax" "0.35 A"
			(at 406.4 31.75 0)
			(effects
				(font
					(size 1.27 1.27)
					(thickness 0.15)
				)
				(justify left bottom)
				(hide yes)
			)
		)
		(property "Size" "1.0x0.5"
			(at 408.94 31.75 0)
			(effects
				(font
					(size 1.27 1.27)
					(thickness 0.15)
				)
				(justify left bottom)
				(hide yes)
			)
		)
		(property "Author" "Antmicro"
			(at 411.48 31.75 0)
			(effects
				(font
					(size 1.27 1.27)
					(thickness 0.15)
				)
				(justify left bottom)
				(hide yes)
			)
		)
		(property "License" "Apache-2.0"
			(at 414.02 31.75 0)
			(effects
				(font
					(size 1.27 1.27)
					(thickness 0.15)
				)
				(justify left bottom)
				(hide yes)
			)
		)
		(pin "2"
		)
		(pin "1"
		)
		(instances
			(project "data-center-rdimm-ddr5-tester"
				(path ""
					(reference "L6")
					(unit 1)
				)
			)
		)
	)
	(symbol
		(lib_id "antmicroMemoryConnectorsPCCardSockets:MicroSD_693071020811")
		(at 191.77 64.77 0)
		(unit 1)
		(exclude_from_sim no)
		(in_bom yes)
		(on_board yes)
		(dnp no)
		(fields_autoplaced yes)
		(property "Reference" "J5"
			(at 213.995 56.515 0)
			(effects
				(font
					(size 1.27 1.27)
					(thickness 0.15)
				)
			)
		)
		(property "Value" "MicroSD_693071020811"
			(at 247.65 69.85 0)
			(effects
				(font
					(size 1.27 1.27)
					(thickness 0.15)
				)
				(justify left bottom)
				(hide yes)
			)
		)
		(property "Footprint" "antmicro-footprints:MicroSD_Wurth_693071020811"
			(at 247.65 72.39 0)
			(effects
				(font
					(size 1.27 1.27)
					(thickness 0.15)
				)
				(justify left bottom)
				(hide yes)
			)
		)
		(property "Datasheet" "https://www.we-online.com/catalog/datasheet/693071020811.pdf"
			(at 247.65 74.93 0)
			(effects
				(font
					(size 1.27 1.27)
					(thickness 0.15)
				)
				(justify left bottom)
				(hide yes)
			)
		)
		(property "Description" ""
			(at 191.77 64.77 0)
			(effects
				(font
					(size 1.27 1.27)
				)
				(hide yes)
			)
		)
		(property "Manufacturer" "Würth Elektronik"
			(at 247.65 77.47 0)
			(effects
				(font
					(size 1.27 1.27)
					(thickness 0.15)
				)
				(justify left bottom)
				(hide yes)
			)
		)
		(property "MPN" "693071020811"
			(at 213.995 59.055 0)
			(effects
				(font
					(size 1.27 1.27)
					(thickness 0.15)
				)
			)
		)
		(property "Author" "Antmicro"
			(at 247.65 82.55 0)
			(effects
				(font
					(size 1.27 1.27)
					(thickness 0.15)
				)
				(justify left bottom)
				(hide yes)
			)
		)
		(property "License" "Apache-2.0"
			(at 247.65 85.09 0)
			(effects
				(font
					(size 1.27 1.27)
					(thickness 0.15)
				)
				(justify left bottom)
				(hide yes)
			)
		)
		(pin "6"
		)
		(pin "8"
		)
		(pin "5"
		)
		(pin "9"
		)
		(pin "4"
		)
		(pin "7"
		)
		(pin "SH"
		)
		(pin "1"
		)
		(pin "2"
		)
		(pin "3"
		)
		(instances
			(project "data-center-rdimm-ddr5-tester"
				(path ""
					(reference "J5")
					(unit 1)
				)
			)
		)
	)
	(symbol
		(lib_id "antmicropower:GND")
		(at 261.62 232.41 0)
		(mirror y)
		(unit 1)
		(exclude_from_sim no)
		(in_bom yes)
		(on_board yes)
		(dnp no)
		(fields_autoplaced yes)
		(property "Reference" "#PWR0226"
			(at 261.62 238.76 0)
			(effects
				(font
					(size 1.27 1.27)
				)
				(hide yes)
			)
		)
		(property "Value" "GND"
			(at 263.525 236.855 0)
			(effects
				(font
					(size 1.27 1.27)
					(thickness 0.15)
				)
				(justify left bottom)
			)
		)
		(property "Footprint" ""
			(at 252.73 240.03 0)
			(effects
				(font
					(size 1.27 1.27)
					(thickness 0.15)
				)
				(justify left bottom)
				(hide yes)
			)
		)
		(property "Datasheet" ""
			(at 252.73 245.11 0)
			(effects
				(font
					(size 1.27 1.27)
					(thickness 0.15)
				)
				(justify left bottom)
				(hide yes)
			)
		)
		(property "Description" ""
			(at 261.62 232.41 0)
			(effects
				(font
					(size 1.27 1.27)
				)
				(hide yes)
			)
		)
		(property "Author" "Antmicro"
			(at 252.73 237.49 0)
			(effects
				(font
					(size 1.27 1.27)
					(thickness 0.15)
				)
				(justify left bottom)
				(hide yes)
			)
		)
		(property "License" "Apache-2.0"
			(at 252.73 240.03 0)
			(effects
				(font
					(size 1.27 1.27)
					(thickness 0.15)
				)
				(justify left bottom)
				(hide yes)
			)
		)
		(pin "1"
		)
		(instances
			(project "data-center-rdimm-ddr5-tester"
				(path ""
					(reference "#PWR0226")
					(unit 1)
				)
			)
		)
	)
	(symbol
		(lib_id "antmicroResistors0402:R_64k9_0402")
		(at 71.12 276.86 180)
		(unit 1)
		(exclude_from_sim no)
		(in_bom no)
		(on_board yes)
		(dnp yes)
		(property "Reference" "R221"
			(at 71.12 275.59 0)
			(effects
				(font
					(size 1.27 1.27)
					(thickness 0.15)
				)
				(justify right)
			)
		)
		(property "Value" "R_64k9_0402"
			(at 50.8 264.16 0)
			(effects
				(font
					(size 1.27 1.27)
					(thickness 0.15)
				)
				(justify left bottom)
				(hide yes)
			)
		)
		(property "Footprint" "antmicro-footprints:R_0402_1005Metric"
			(at 50.8 261.62 0)
			(effects
				(font
					(size 1.27 1.27)
					(thickness 0.15)
				)
				(justify left bottom)
				(hide yes)
			)
		)
		(property "Datasheet" "https://www.bourns.com/docs/product-datasheets/cr.pdf"
			(at 50.8 259.08 0)
			(effects
				(font
					(size 1.27 1.27)
					(thickness 0.15)
				)
				(justify left bottom)
				(hide yes)
			)
		)
		(property "Description" ""
			(at 71.12 276.86 0)
			(effects
				(font
					(size 1.27 1.27)
				)
				(hide yes)
			)
		)
		(property "MPN" "CR0402-FX-6492GLF"
			(at 50.8 256.54 0)
			(effects
				(font
					(size 1.27 1.27)
					(thickness 0.15)
				)
				(justify left bottom)
				(hide yes)
			)
		)
		(property "Manufacturer" "Bourns"
			(at 50.8 254 0)
			(effects
				(font
					(size 1.27 1.27)
					(thickness 0.15)
				)
				(justify left bottom)
				(hide yes)
			)
		)
		(property "License" "Apache-2.0"
			(at 50.8 251.46 0)
			(effects
				(font
					(size 1.27 1.27)
					(thickness 0.15)
				)
				(justify left bottom)
				(hide yes)
			)
		)
		(property "Author" "Antmicro"
			(at 50.8 248.92 0)
			(effects
				(font
					(size 1.27 1.27)
					(thickness 0.15)
				)
				(justify left bottom)
				(hide yes)
			)
		)
		(property "Val" "64k9"
			(at 60.96 275.59 0)
			(effects
				(font
					(size 1.27 1.27)
					(thickness 0.15)
				)
				(justify right)
			)
		)
		(property "Tolerance" "1%"
			(at 50.8 266.7 0)
			(effects
				(font
					(size 1.27 1.27)
				)
				(justify left bottom)
				(hide yes)
			)
		)
		(pin "2"
		)
		(pin "1"
		)
		(instances
			(project "data-center-rdimm-ddr5-tester"
				(path ""
					(reference "R221")
					(unit 1)
				)
			)
		)
	)
	(symbol
		(lib_id "antmicropower:GND")
		(at 386.08 245.11 0)
		(unit 1)
		(exclude_from_sim no)
		(in_bom yes)
		(on_board yes)
		(dnp no)
		(property "Reference" "#PWR0504"
			(at 386.08 251.46 0)
			(effects
				(font
					(size 1.27 1.27)
				)
				(hide yes)
			)
		)
		(property "Value" "GND"
			(at 384.175 249.555 0)
			(effects
				(font
					(size 1.27 1.27)
					(thickness 0.15)
				)
				(justify left bottom)
			)
		)
		(property "Footprint" ""
			(at 394.97 252.73 0)
			(effects
				(font
					(size 1.27 1.27)
					(thickness 0.15)
				)
				(justify left bottom)
				(hide yes)
			)
		)
		(property "Datasheet" ""
			(at 394.97 257.81 0)
			(effects
				(font
					(size 1.27 1.27)
					(thickness 0.15)
				)
				(justify left bottom)
				(hide yes)
			)
		)
		(property "Description" ""
			(at 386.08 245.11 0)
			(effects
				(font
					(size 1.27 1.27)
				)
				(hide yes)
			)
		)
		(property "Author" "Antmicro"
			(at 394.97 250.19 0)
			(effects
				(font
					(size 1.27 1.27)
					(thickness 0.15)
				)
				(justify left bottom)
				(hide yes)
			)
		)
		(property "License" "Apache-2.0"
			(at 394.97 252.73 0)
			(effects
				(font
					(size 1.27 1.27)
					(thickness 0.15)
				)
				(justify left bottom)
				(hide yes)
			)
		)
		(pin "1"
		)
		(instances
			(project "data-center-rdimm-ddr5-tester"
				(path ""
					(reference "#PWR0504")
					(unit 1)
				)
			)
		)
	)
	(symbol
		(lib_id "antmicroFixedInductors:L_20n_0.35A_0402")
		(at 345.44 45.72 90)
		(unit 1)
		(exclude_from_sim no)
		(in_bom yes)
		(on_board yes)
		(dnp no)
		(property "Reference" "L9"
			(at 346.71 41.91 90)
			(effects
				(font
					(size 1.27 1.27)
					(thickness 0.15)
				)
				(justify right)
			)
		)
		(property "Value" "L_20n_0.35A_0402"
			(at 347.98 31.75 0)
			(effects
				(font
					(size 1.27 1.27)
					(thickness 0.15)
				)
				(justify left bottom)
				(hide yes)
			)
		)
		(property "Footprint" "antmicro-footprints:L_0402_1005Metric"
			(at 353.06 31.75 0)
			(effects
				(font
					(size 1.27 1.27)
					(thickness 0.15)
				)
				(justify left bottom)
				(hide yes)
			)
		)
		(property "Datasheet" "https://product.tdk.com/system/files/dam/doc/product/inductor/inductor/smd/catalog/inductor_automotive_high-frequency_mlg1005s_en.pdf?ref_disty=mouser"
			(at 355.6 31.75 0)
			(effects
				(font
					(size 1.27 1.27)
					(thickness 0.15)
				)
				(justify left bottom)
				(hide yes)
			)
		)
		(property "Description" ""
			(at 345.44 45.72 0)
			(effects
				(font
					(size 1.27 1.27)
				)
				(hide yes)
			)
		)
		(property "Val" "20n/0.35A"
			(at 342.9 40.005 0)
			(effects
				(font
					(size 1.27 1.27)
					(thickness 0.15)
				)
				(justify right)
			)
		)
		(property "Manufacturer" "TDK"
			(at 358.14 31.75 0)
			(effects
				(font
					(size 1.27 1.27)
					(thickness 0.15)
				)
				(justify left bottom)
				(hide yes)
			)
		)
		(property "MPN" "MLG1005S20NJTD25"
			(at 360.68 31.75 0)
			(effects
				(font
					(size 1.27 1.27)
					(thickness 0.15)
				)
				(justify left bottom)
				(hide yes)
			)
		)
		(property "ISat" ""
			(at 361.95 31.75 0)
			(effects
				(font
					(size 1.27 1.27)
				)
				(justify left)
				(hide yes)
			)
		)
		(property "IMax" "0.35 A"
			(at 365.76 31.75 0)
			(effects
				(font
					(size 1.27 1.27)
					(thickness 0.15)
				)
				(justify left bottom)
				(hide yes)
			)
		)
		(property "Size" "1.0x0.5"
			(at 368.3 31.75 0)
			(effects
				(font
					(size 1.27 1.27)
					(thickness 0.15)
				)
				(justify left bottom)
				(hide yes)
			)
		)
		(property "Author" "Antmicro"
			(at 370.84 31.75 0)
			(effects
				(font
					(size 1.27 1.27)
					(thickness 0.15)
				)
				(justify left bottom)
				(hide yes)
			)
		)
		(property "License" "Apache-2.0"
			(at 373.38 31.75 0)
			(effects
				(font
					(size 1.27 1.27)
					(thickness 0.15)
				)
				(justify left bottom)
				(hide yes)
			)
		)
		(pin "2"
		)
		(pin "1"
		)
		(instances
			(project "data-center-rdimm-ddr5-tester"
				(path ""
					(reference "L9")
					(unit 1)
				)
			)
		)
	)
	(symbol
		(lib_id "antmicroResistors0402:R_64k9_0402")
		(at 71.12 271.78 180)
		(unit 1)
		(exclude_from_sim no)
		(in_bom yes)
		(on_board yes)
		(dnp no)
		(property "Reference" "R219"
			(at 71.12 270.51 0)
			(effects
				(font
					(size 1.27 1.27)
					(thickness 0.15)
				)
				(justify right)
			)
		)
		(property "Value" "R_64k9_0402"
			(at 50.8 259.08 0)
			(effects
				(font
					(size 1.27 1.27)
					(thickness 0.15)
				)
				(justify left bottom)
				(hide yes)
			)
		)
		(property "Footprint" "antmicro-footprints:R_0402_1005Metric"
			(at 50.8 256.54 0)
			(effects
				(font
					(size 1.27 1.27)
					(thickness 0.15)
				)
				(justify left bottom)
				(hide yes)
			)
		)
		(property "Datasheet" "https://www.bourns.com/docs/product-datasheets/cr.pdf"
			(at 50.8 254 0)
			(effects
				(font
					(size 1.27 1.27)
					(thickness 0.15)
				)
				(justify left bottom)
				(hide yes)
			)
		)
		(property "Description" ""
			(at 71.12 271.78 0)
			(effects
				(font
					(size 1.27 1.27)
				)
				(hide yes)
			)
		)
		(property "MPN" "CR0402-FX-6492GLF"
			(at 50.8 251.46 0)
			(effects
				(font
					(size 1.27 1.27)
					(thickness 0.15)
				)
				(justify left bottom)
				(hide yes)
			)
		)
		(property "Manufacturer" "Bourns"
			(at 50.8 248.92 0)
			(effects
				(font
					(size 1.27 1.27)
					(thickness 0.15)
				)
				(justify left bottom)
				(hide yes)
			)
		)
		(property "License" "Apache-2.0"
			(at 50.8 246.38 0)
			(effects
				(font
					(size 1.27 1.27)
					(thickness 0.15)
				)
				(justify left bottom)
				(hide yes)
			)
		)
		(property "Author" "Antmicro"
			(at 50.8 243.84 0)
			(effects
				(font
					(size 1.27 1.27)
					(thickness 0.15)
				)
				(justify left bottom)
				(hide yes)
			)
		)
		(property "Val" "64k9"
			(at 60.96 270.51 0)
			(effects
				(font
					(size 1.27 1.27)
					(thickness 0.15)
				)
				(justify right)
			)
		)
		(property "Tolerance" "1%"
			(at 50.8 261.62 0)
			(effects
				(font
					(size 1.27 1.27)
				)
				(justify left bottom)
				(hide yes)
			)
		)
		(pin "2"
		)
		(pin "1"
		)
		(instances
			(project "data-center-rdimm-ddr5-tester"
				(path ""
					(reference "R219")
					(unit 1)
				)
			)
		)
	)
	(symbol
		(lib_id "antmicroFerriteBeadsandChips:FB_120Z_1.3A_Murata-BLM15PD_0402")
		(at 303.53 31.75 0)
		(unit 1)
		(exclude_from_sim no)
		(in_bom yes)
		(on_board yes)
		(dnp no)
		(property "Reference" "FB7"
			(at 309.88 30.48 0)
			(effects
				(font
					(size 1.27 1.27)
					(thickness 0.15)
				)
			)
		)
		(property "Value" "FB_120Z_1.3A_Murata-BLM15PD_0402"
			(at 317.5 34.29 0)
			(effects
				(font
					(size 1.27 1.27)
					(thickness 0.15)
				)
				(justify left bottom)
				(hide yes)
			)
		)
		(property "Footprint" "antmicro-footprints:FB_0402_1005Metric"
			(at 317.5 39.37 0)
			(effects
				(font
					(size 1.27 1.27)
					(thickness 0.15)
				)
				(justify left bottom)
				(hide yes)
			)
		)
		(property "Datasheet" "https://www.murata.com/en-us/products/productdata/8796740059166/ENFA0018.pdf"
			(at 317.5 41.91 0)
			(effects
				(font
					(size 1.27 1.27)
					(thickness 0.15)
				)
				(justify left bottom)
				(hide yes)
			)
		)
		(property "Description" ""
			(at 303.53 31.75 0)
			(effects
				(font
					(size 1.27 1.27)
				)
				(hide yes)
			)
		)
		(property "Val" "120Z/1.3A"
			(at 304.165 34.925 0)
			(effects
				(font
					(size 1.27 1.27)
				)
			)
		)
		(property "MPN" "BLM15PD121SN1D"
			(at 317.5 44.45 0)
			(effects
				(font
					(size 1.27 1.27)
					(thickness 0.15)
				)
				(justify left bottom)
				(hide yes)
			)
		)
		(property "Manufacturer" "Murata"
			(at 317.5 46.99 0)
			(effects
				(font
					(size 1.27 1.27)
					(thickness 0.15)
				)
				(justify left bottom)
				(hide yes)
			)
		)
		(property "Current" ""
			(at 323.85 54.61 0)
			(effects
				(font
					(size 1.27 1.27)
					(thickness 0.15)
				)
				(justify left bottom)
				(hide yes)
			)
		)
		(property "Author" "Antmicro"
			(at 317.5 49.53 0)
			(effects
				(font
					(size 1.27 1.27)
					(thickness 0.15)
				)
				(justify left bottom)
				(hide yes)
			)
		)
		(property "License" "Apache-2.0"
			(at 317.5 52.07 0)
			(effects
				(font
					(size 1.27 1.27)
					(thickness 0.15)
				)
				(justify left bottom)
				(hide yes)
			)
		)
		(pin "2"
		)
		(pin "1"
		)
		(instances
			(project "data-center-rdimm-ddr5-tester"
				(path ""
					(reference "FB7")
					(unit 1)
				)
			)
		)
	)
	(symbol
		(lib_id "antmicropower:GND")
		(at 234.95 93.98 0)
		(mirror y)
		(unit 1)
		(exclude_from_sim no)
		(in_bom yes)
		(on_board yes)
		(dnp no)
		(fields_autoplaced yes)
		(property "Reference" "#PWR0233"
			(at 234.95 100.33 0)
			(effects
				(font
					(size 1.27 1.27)
				)
				(hide yes)
			)
		)
		(property "Value" "GND"
			(at 236.855 98.425 0)
			(effects
				(font
					(size 1.27 1.27)
					(thickness 0.15)
				)
				(justify left bottom)
			)
		)
		(property "Footprint" ""
			(at 226.06 101.6 0)
			(effects
				(font
					(size 1.27 1.27)
					(thickness 0.15)
				)
				(justify left bottom)
				(hide yes)
			)
		)
		(property "Datasheet" ""
			(at 226.06 106.68 0)
			(effects
				(font
					(size 1.27 1.27)
					(thickness 0.15)
				)
				(justify left bottom)
				(hide yes)
			)
		)
		(property "Description" ""
			(at 234.95 93.98 0)
			(effects
				(font
					(size 1.27 1.27)
				)
				(hide yes)
			)
		)
		(property "Author" "Antmicro"
			(at 226.06 99.06 0)
			(effects
				(font
					(size 1.27 1.27)
					(thickness 0.15)
				)
				(justify left bottom)
				(hide yes)
			)
		)
		(property "License" "Apache-2.0"
			(at 226.06 101.6 0)
			(effects
				(font
					(size 1.27 1.27)
					(thickness 0.15)
				)
				(justify left bottom)
				(hide yes)
			)
		)
		(pin "1"
		)
		(instances
			(project "data-center-rdimm-ddr5-tester"
				(path ""
					(reference "#PWR0233")
					(unit 1)
				)
			)
		)
	)
	(symbol
		(lib_id "antmicroResistors0402:R_49k9_0402")
		(at 353.06 38.1 90)
		(unit 1)
		(exclude_from_sim no)
		(in_bom yes)
		(on_board yes)
		(dnp no)
		(fields_autoplaced yes)
		(property "Reference" "R34"
			(at 354.965 34.29 90)
			(effects
				(font
					(size 1.27 1.27)
					(thickness 0.15)
				)
				(justify right)
			)
		)
		(property "Value" "R_49k9_0402"
			(at 365.76 17.78 0)
			(effects
				(font
					(size 1.27 1.27)
					(thickness 0.15)
				)
				(justify left bottom)
				(hide yes)
			)
		)
		(property "Footprint" "antmicro-footprints:R_0402_1005Metric"
			(at 368.3 17.78 0)
			(effects
				(font
					(size 1.27 1.27)
					(thickness 0.15)
				)
				(justify left bottom)
				(hide yes)
			)
		)
		(property "Datasheet" "https://www.bourns.com/docs/product-datasheets/cr.pdf"
			(at 370.84 17.78 0)
			(effects
				(font
					(size 1.27 1.27)
					(thickness 0.15)
				)
				(justify left bottom)
				(hide yes)
			)
		)
		(property "Description" ""
			(at 353.06 38.1 0)
			(effects
				(font
					(size 1.27 1.27)
				)
				(hide yes)
			)
		)
		(property "MPN" "CR0402-FX-4992GLF"
			(at 373.38 17.78 0)
			(effects
				(font
					(size 1.27 1.27)
					(thickness 0.15)
				)
				(justify left bottom)
				(hide yes)
			)
		)
		(property "Manufacturer" "Bourns"
			(at 375.92 17.78 0)
			(effects
				(font
					(size 1.27 1.27)
					(thickness 0.15)
				)
				(justify left bottom)
				(hide yes)
			)
		)
		(property "License" "Apache-2.0"
			(at 378.46 17.78 0)
			(effects
				(font
					(size 1.27 1.27)
					(thickness 0.15)
				)
				(justify left bottom)
				(hide yes)
			)
		)
		(property "Author" "Antmicro"
			(at 381 17.78 0)
			(effects
				(font
					(size 1.27 1.27)
					(thickness 0.15)
				)
				(justify left bottom)
				(hide yes)
			)
		)
		(property "Val" "49k9"
			(at 354.965 36.83 90)
			(effects
				(font
					(size 1.27 1.27)
					(thickness 0.15)
				)
				(justify right)
			)
		)
		(property "Tolerance" "1%"
			(at 363.22 17.78 0)
			(effects
				(font
					(size 1.27 1.27)
				)
				(justify left bottom)
				(hide yes)
			)
		)
		(pin "1"
		)
		(pin "2"
		)
		(instances
			(project "data-center-rdimm-ddr5-tester"
				(path ""
					(reference "R34")
					(unit 1)
				)
			)
		)
	)
	(symbol
		(lib_id "antmicropower:GND")
		(at 173.99 275.59 0)
		(unit 1)
		(exclude_from_sim no)
		(in_bom yes)
		(on_board yes)
		(dnp no)
		(property "Reference" "#PWR0460"
			(at 182.88 278.13 0)
			(effects
				(font
					(size 1.27 1.27)
					(thickness 0.15)
				)
				(justify left bottom)
				(hide yes)
			)
		)
		(property "Value" "GND"
			(at 177.8 276.86 0)
			(effects
				(font
					(size 1.27 1.27)
					(thickness 0.15)
				)
			)
		)
		(property "Footprint" ""
			(at 182.88 283.21 0)
			(effects
				(font
					(size 1.27 1.27)
					(thickness 0.15)
				)
				(justify left bottom)
				(hide yes)
			)
		)
		(property "Datasheet" ""
			(at 182.88 288.29 0)
			(effects
				(font
					(size 1.27 1.27)
					(thickness 0.15)
				)
				(justify left bottom)
				(hide yes)
			)
		)
		(property "Description" ""
			(at 173.99 275.59 0)
			(effects
				(font
					(size 1.27 1.27)
				)
				(hide yes)
			)
		)
		(property "Author" "Antmicro"
			(at 182.88 283.21 0)
			(effects
				(font
					(size 1.27 1.27)
					(thickness 0.15)
				)
				(justify left bottom)
				(hide yes)
			)
		)
		(property "License" "Apache-2.0"
			(at 182.88 285.75 0)
			(effects
				(font
					(size 1.27 1.27)
					(thickness 0.15)
				)
				(justify left bottom)
				(hide yes)
			)
		)
		(pin "1"
		)
		(instances
			(project "data-center-rdimm-ddr5-tester"
				(path ""
					(reference "#PWR0460")
					(unit 1)
				)
			)
		)
	)
	(symbol
		(lib_id "antmicropower:GND")
		(at 119.38 275.59 0)
		(unit 1)
		(exclude_from_sim no)
		(in_bom yes)
		(on_board yes)
		(dnp no)
		(property "Reference" "#PWR0458"
			(at 128.27 278.13 0)
			(effects
				(font
					(size 1.27 1.27)
					(thickness 0.15)
				)
				(justify left bottom)
				(hide yes)
			)
		)
		(property "Value" "GND"
			(at 123.19 276.86 0)
			(effects
				(font
					(size 1.27 1.27)
					(thickness 0.15)
				)
			)
		)
		(property "Footprint" ""
			(at 128.27 283.21 0)
			(effects
				(font
					(size 1.27 1.27)
					(thickness 0.15)
				)
				(justify left bottom)
				(hide yes)
			)
		)
		(property "Datasheet" ""
			(at 128.27 288.29 0)
			(effects
				(font
					(size 1.27 1.27)
					(thickness 0.15)
				)
				(justify left bottom)
				(hide yes)
			)
		)
		(property "Description" ""
			(at 119.38 275.59 0)
			(effects
				(font
					(size 1.27 1.27)
				)
				(hide yes)
			)
		)
		(property "Author" "Antmicro"
			(at 128.27 283.21 0)
			(effects
				(font
					(size 1.27 1.27)
					(thickness 0.15)
				)
				(justify left bottom)
				(hide yes)
			)
		)
		(property "License" "Apache-2.0"
			(at 128.27 285.75 0)
			(effects
				(font
					(size 1.27 1.27)
					(thickness 0.15)
				)
				(justify left bottom)
				(hide yes)
			)
		)
		(pin "1"
		)
		(instances
			(project "data-center-rdimm-ddr5-tester"
				(path ""
					(reference "#PWR0458")
					(unit 1)
				)
			)
		)
	)
	(symbol
		(lib_id "antmicropower:GND")
		(at 85.09 67.31 0)
		(unit 1)
		(exclude_from_sim no)
		(in_bom yes)
		(on_board yes)
		(dnp no)
		(fields_autoplaced yes)
		(property "Reference" "#PWR0481"
			(at 93.98 69.85 0)
			(effects
				(font
					(size 1.27 1.27)
					(thickness 0.15)
				)
				(justify left bottom)
				(hide yes)
			)
		)
		(property "Value" "GND"
			(at 85.09 71.755 0)
			(effects
				(font
					(size 1.27 1.27)
					(thickness 0.15)
				)
			)
		)
		(property "Footprint" ""
			(at 93.98 74.93 0)
			(effects
				(font
					(size 1.27 1.27)
					(thickness 0.15)
				)
				(justify left bottom)
				(hide yes)
			)
		)
		(property "Datasheet" ""
			(at 93.98 80.01 0)
			(effects
				(font
					(size 1.27 1.27)
					(thickness 0.15)
				)
				(justify left bottom)
				(hide yes)
			)
		)
		(property "Description" ""
			(at 85.09 67.31 0)
			(effects
				(font
					(size 1.27 1.27)
				)
				(hide yes)
			)
		)
		(property "Author" "Antmicro"
			(at 93.98 74.93 0)
			(effects
				(font
					(size 1.27 1.27)
					(thickness 0.15)
				)
				(justify left bottom)
				(hide yes)
			)
		)
		(property "License" "Apache-2.0"
			(at 93.98 77.47 0)
			(effects
				(font
					(size 1.27 1.27)
					(thickness 0.15)
				)
				(justify left bottom)
				(hide yes)
			)
		)
		(pin "1"
		)
		(instances
			(project "data-center-rdimm-ddr5-tester"
				(path ""
					(reference "#PWR0481")
					(unit 1)
				)
			)
		)
	)
	(symbol
		(lib_id "antmicropower:+1V8")
		(at 53.34 113.03 0)
		(unit 1)
		(exclude_from_sim no)
		(in_bom yes)
		(on_board yes)
		(dnp no)
		(fields_autoplaced yes)
		(property "Reference" "#PWR0492"
			(at 68.58 115.57 0)
			(effects
				(font
					(size 1.27 1.27)
					(thickness 0.15)
				)
				(justify left bottom)
				(hide yes)
			)
		)
		(property "Value" "+1V8"
			(at 53.34 109.22 0)
			(effects
				(font
					(size 1.27 1.27)
					(thickness 0.15)
				)
			)
		)
		(property "Footprint" ""
			(at 68.58 120.65 0)
			(effects
				(font
					(size 1.27 1.27)
					(thickness 0.15)
				)
				(justify left bottom)
				(hide yes)
			)
		)
		(property "Datasheet" ""
			(at 68.58 123.19 0)
			(effects
				(font
					(size 1.27 1.27)
					(thickness 0.15)
				)
				(justify left bottom)
				(hide yes)
			)
		)
		(property "Description" ""
			(at 53.34 113.03 0)
			(effects
				(font
					(size 1.27 1.27)
				)
				(hide yes)
			)
		)
		(property "Author" "Antmicro"
			(at 68.58 118.11 0)
			(effects
				(font
					(size 1.27 1.27)
					(thickness 0.15)
				)
				(justify left bottom)
				(hide yes)
			)
		)
		(property "License" "Apache-2.0"
			(at 68.58 120.65 0)
			(effects
				(font
					(size 1.27 1.27)
					(thickness 0.15)
				)
				(justify left bottom)
				(hide yes)
			)
		)
		(pin "1"
		)
		(instances
			(project "data-center-rdimm-ddr5-tester"
				(path ""
					(reference "#PWR0492")
					(unit 1)
				)
			)
		)
	)
	(symbol
		(lib_id "antmicroCapacitors0402:C_100n_0402")
		(at 114.3 43.18 90)
		(unit 1)
		(exclude_from_sim no)
		(in_bom yes)
		(on_board yes)
		(dnp no)
		(fields_autoplaced yes)
		(property "Reference" "C299"
			(at 117.475 39.3636 90)
			(effects
				(font
					(size 1.27 1.27)
					(thickness 0.15)
				)
				(justify right)
			)
		)
		(property "Value" "C_100n_0402"
			(at 124.46 22.86 0)
			(effects
				(font
					(size 1.27 1.27)
					(thickness 0.15)
				)
				(justify left bottom)
				(hide yes)
			)
		)
		(property "Footprint" "antmicro-footprints:C_0402_1005Metric"
			(at 127 22.86 0)
			(effects
				(font
					(size 1.27 1.27)
					(thickness 0.15)
				)
				(justify left bottom)
				(hide yes)
			)
		)
		(property "Datasheet" "https://www.murata.com/products/productdetail?partno=GRM155R61H104KE14%23"
			(at 129.54 22.86 0)
			(effects
				(font
					(size 1.27 1.27)
					(thickness 0.15)
				)
				(justify left bottom)
				(hide yes)
			)
		)
		(property "Description" ""
			(at 114.3 43.18 0)
			(effects
				(font
					(size 1.27 1.27)
				)
				(hide yes)
			)
		)
		(property "MPN" "GRM155R61H104KE14D"
			(at 132.08 22.86 0)
			(effects
				(font
					(size 1.27 1.27)
					(thickness 0.15)
				)
				(justify left bottom)
				(hide yes)
			)
		)
		(property "Manufacturer" "Murata"
			(at 134.62 22.86 0)
			(effects
				(font
					(size 1.27 1.27)
					(thickness 0.15)
				)
				(justify left bottom)
				(hide yes)
			)
		)
		(property "License" "Apache-2.0"
			(at 137.16 22.86 0)
			(effects
				(font
					(size 1.27 1.27)
					(thickness 0.15)
				)
				(justify left bottom)
				(hide yes)
			)
		)
		(property "Author" "Antmicro"
			(at 139.7 22.86 0)
			(effects
				(font
					(size 1.27 1.27)
					(thickness 0.15)
				)
				(justify left bottom)
				(hide yes)
			)
		)
		(property "Val" "100n"
			(at 117.475 41.9036 90)
			(effects
				(font
					(size 1.27 1.27)
					(thickness 0.15)
				)
				(justify right)
			)
		)
		(property "Voltage" "50V"
			(at 142.24 22.86 0)
			(effects
				(font
					(size 1.27 1.27)
				)
				(justify left bottom)
				(hide yes)
			)
		)
		(property "Dielectric" "X5R"
			(at 144.78 22.86 0)
			(effects
				(font
					(size 1.27 1.27)
				)
				(justify left bottom)
				(hide yes)
			)
		)
		(pin "1"
		)
		(pin "2"
		)
		(instances
			(project "data-center-rdimm-ddr5-tester"
				(path ""
					(reference "C299")
					(unit 1)
				)
			)
		)
	)
	(symbol
		(lib_id "antmicropower:PWR_FLAG")
		(at 182.88 210.82 0)
		(unit 1)
		(exclude_from_sim no)
		(in_bom yes)
		(on_board yes)
		(dnp no)
		(fields_autoplaced yes)
		(property "Reference" "#FLG02"
			(at 182.88 208.915 0)
			(effects
				(font
					(size 1.27 1.27)
				)
				(hide yes)
			)
		)
		(property "Value" "PWR_FLAG"
			(at 182.88 207.01 0)
			(effects
				(font
					(size 1.27 1.27)
				)
			)
		)
		(property "Footprint" ""
			(at 182.88 210.82 0)
			(effects
				(font
					(size 1.27 1.27)
				)
				(hide yes)
			)
		)
		(property "Datasheet" ""
			(at 182.88 210.82 0)
			(effects
				(font
					(size 1.27 1.27)
				)
				(hide yes)
			)
		)
		(property "Description" ""
			(at 182.88 210.82 0)
			(effects
				(font
					(size 1.27 1.27)
				)
				(hide yes)
			)
		)
		(pin "1"
		)
		(instances
			(project "data-center-rdimm-ddr5-tester"
				(path ""
					(reference "#FLG02")
					(unit 1)
				)
			)
		)
	)
	(symbol
		(lib_id "antmicroResistors0402:R_64k9_0402")
		(at 39.37 276.86 180)
		(unit 1)
		(exclude_from_sim no)
		(in_bom no)
		(on_board yes)
		(dnp yes)
		(property "Reference" "R230"
			(at 39.37 275.59 0)
			(effects
				(font
					(size 1.27 1.27)
					(thickness 0.15)
				)
				(justify right)
			)
		)
		(property "Value" "R_64k9_0402"
			(at 19.05 264.16 0)
			(effects
				(font
					(size 1.27 1.27)
					(thickness 0.15)
				)
				(justify left bottom)
				(hide yes)
			)
		)
		(property "Footprint" "antmicro-footprints:R_0402_1005Metric"
			(at 19.05 261.62 0)
			(effects
				(font
					(size 1.27 1.27)
					(thickness 0.15)
				)
				(justify left bottom)
				(hide yes)
			)
		)
		(property "Datasheet" "https://www.bourns.com/docs/product-datasheets/cr.pdf"
			(at 19.05 259.08 0)
			(effects
				(font
					(size 1.27 1.27)
					(thickness 0.15)
				)
				(justify left bottom)
				(hide yes)
			)
		)
		(property "Description" ""
			(at 39.37 276.86 0)
			(effects
				(font
					(size 1.27 1.27)
				)
				(hide yes)
			)
		)
		(property "MPN" "CR0402-FX-6492GLF"
			(at 19.05 256.54 0)
			(effects
				(font
					(size 1.27 1.27)
					(thickness 0.15)
				)
				(justify left bottom)
				(hide yes)
			)
		)
		(property "Manufacturer" "Bourns"
			(at 19.05 254 0)
			(effects
				(font
					(size 1.27 1.27)
					(thickness 0.15)
				)
				(justify left bottom)
				(hide yes)
			)
		)
		(property "License" "Apache-2.0"
			(at 19.05 251.46 0)
			(effects
				(font
					(size 1.27 1.27)
					(thickness 0.15)
				)
				(justify left bottom)
				(hide yes)
			)
		)
		(property "Author" "Antmicro"
			(at 19.05 248.92 0)
			(effects
				(font
					(size 1.27 1.27)
					(thickness 0.15)
				)
				(justify left bottom)
				(hide yes)
			)
		)
		(property "Val" "64k9"
			(at 29.21 275.59 0)
			(effects
				(font
					(size 1.27 1.27)
					(thickness 0.15)
				)
				(justify right)
			)
		)
		(property "Tolerance" "1%"
			(at 19.05 266.7 0)
			(effects
				(font
					(size 1.27 1.27)
				)
				(justify left bottom)
				(hide yes)
			)
		)
		(pin "2"
		)
		(pin "1"
		)
		(instances
			(project "data-center-rdimm-ddr5-tester"
				(path ""
					(reference "R230")
					(unit 1)
				)
			)
		)
	)
	(symbol
		(lib_id "antmicropower:GND")
		(at 78.74 278.13 0)
		(unit 1)
		(exclude_from_sim no)
		(in_bom yes)
		(on_board yes)
		(dnp no)
		(property "Reference" "#PWR0474"
			(at 78.74 284.48 0)
			(effects
				(font
					(size 1.27 1.27)
				)
				(hide yes)
			)
		)
		(property "Value" "GND"
			(at 76.835 282.575 0)
			(effects
				(font
					(size 1.27 1.27)
					(thickness 0.15)
				)
				(justify left bottom)
			)
		)
		(property "Footprint" ""
			(at 87.63 285.75 0)
			(effects
				(font
					(size 1.27 1.27)
					(thickness 0.15)
				)
				(justify left bottom)
				(hide yes)
			)
		)
		(property "Datasheet" ""
			(at 87.63 290.83 0)
			(effects
				(font
					(size 1.27 1.27)
					(thickness 0.15)
				)
				(justify left bottom)
				(hide yes)
			)
		)
		(property "Description" ""
			(at 78.74 278.13 0)
			(effects
				(font
					(size 1.27 1.27)
				)
				(hide yes)
			)
		)
		(property "Author" "Antmicro"
			(at 87.63 283.21 0)
			(effects
				(font
					(size 1.27 1.27)
					(thickness 0.15)
				)
				(justify left bottom)
				(hide yes)
			)
		)
		(property "License" "Apache-2.0"
			(at 87.63 285.75 0)
			(effects
				(font
					(size 1.27 1.27)
					(thickness 0.15)
				)
				(justify left bottom)
				(hide yes)
			)
		)
		(pin "1"
		)
		(instances
			(project "data-center-rdimm-ddr5-tester"
				(path ""
					(reference "#PWR0474")
					(unit 1)
				)
			)
		)
	)
	(symbol
		(lib_id "antmicroCapacitors0402:C_100n_0402")
		(at 153.67 264.16 270)
		(unit 1)
		(exclude_from_sim no)
		(in_bom yes)
		(on_board yes)
		(dnp no)
		(property "Reference" "C280"
			(at 152.4 270.51 0)
			(effects
				(font
					(size 1.27 1.27)
					(thickness 0.15)
				)
			)
		)
		(property "Value" "C_100n_0402"
			(at 143.51 284.48 0)
			(effects
				(font
					(size 1.27 1.27)
					(thickness 0.15)
				)
				(justify left bottom)
				(hide yes)
			)
		)
		(property "Footprint" "antmicro-footprints:C_0402_1005Metric"
			(at 140.97 284.48 0)
			(effects
				(font
					(size 1.27 1.27)
					(thickness 0.15)
				)
				(justify left bottom)
				(hide yes)
			)
		)
		(property "Datasheet" "https://www.murata.com/products/productdetail?partno=GRM155R61H104KE14%23"
			(at 138.43 284.48 0)
			(effects
				(font
					(size 1.27 1.27)
					(thickness 0.15)
				)
				(justify left bottom)
				(hide yes)
			)
		)
		(property "Description" ""
			(at 153.67 264.16 0)
			(effects
				(font
					(size 1.27 1.27)
				)
				(hide yes)
			)
		)
		(property "MPN" "GRM155R61H104KE14D"
			(at 135.89 284.48 0)
			(effects
				(font
					(size 1.27 1.27)
					(thickness 0.15)
				)
				(justify left bottom)
				(hide yes)
			)
		)
		(property "Manufacturer" "Murata"
			(at 133.35 284.48 0)
			(effects
				(font
					(size 1.27 1.27)
					(thickness 0.15)
				)
				(justify left bottom)
				(hide yes)
			)
		)
		(property "License" "Apache-2.0"
			(at 130.81 284.48 0)
			(effects
				(font
					(size 1.27 1.27)
					(thickness 0.15)
				)
				(justify left bottom)
				(hide yes)
			)
		)
		(property "Author" "Antmicro"
			(at 128.27 284.48 0)
			(effects
				(font
					(size 1.27 1.27)
					(thickness 0.15)
				)
				(justify left bottom)
				(hide yes)
			)
		)
		(property "Val" "100n"
			(at 151.13 260.35 0)
			(effects
				(font
					(size 1.27 1.27)
					(thickness 0.15)
				)
				(justify left bottom)
			)
		)
		(property "Voltage" "50V"
			(at 125.73 284.48 0)
			(effects
				(font
					(size 1.27 1.27)
				)
				(justify left bottom)
				(hide yes)
			)
		)
		(property "Dielectric" "X5R"
			(at 123.19 284.48 0)
			(effects
				(font
					(size 1.27 1.27)
				)
				(justify left bottom)
				(hide yes)
			)
		)
		(property "Public" ""
			(at 120.65 284.48 0)
			(effects
				(font
					(size 1.27 1.27)
				)
				(justify left bottom)
				(hide yes)
			)
		)
		(pin "2"
		)
		(pin "1"
		)
		(instances
			(project "data-center-rdimm-ddr5-tester"
				(path ""
					(reference "C280")
					(unit 1)
				)
			)
		)
	)
	(symbol
		(lib_id "antmicroResistors0402:R_2k2_0402")
		(at 140.97 185.42 90)
		(unit 1)
		(exclude_from_sim no)
		(in_bom yes)
		(on_board yes)
		(dnp no)
		(property "Reference" "R72"
			(at 139.065 181.61 90)
			(effects
				(font
					(size 1.27 1.27)
					(thickness 0.15)
				)
				(justify left)
			)
		)
		(property "Value" "R_2k2_0402"
			(at 153.67 165.1 0)
			(effects
				(font
					(size 1.27 1.27)
					(thickness 0.15)
				)
				(justify left bottom)
				(hide yes)
			)
		)
		(property "Footprint" "antmicro-footprints:R_0402_1005Metric"
			(at 156.21 165.1 0)
			(effects
				(font
					(size 1.27 1.27)
					(thickness 0.15)
				)
				(justify left bottom)
				(hide yes)
			)
		)
		(property "Datasheet" "https://www.bourns.com/docs/product-datasheets/cr.pdf"
			(at 158.75 165.1 0)
			(effects
				(font
					(size 1.27 1.27)
					(thickness 0.15)
				)
				(justify left bottom)
				(hide yes)
			)
		)
		(property "Description" ""
			(at 140.97 185.42 0)
			(effects
				(font
					(size 1.27 1.27)
				)
				(hide yes)
			)
		)
		(property "MPN" "CR0402-FX-2201GLF"
			(at 161.29 165.1 0)
			(effects
				(font
					(size 1.27 1.27)
					(thickness 0.15)
				)
				(justify left bottom)
				(hide yes)
			)
		)
		(property "Manufacturer" "Bourns"
			(at 163.83 165.1 0)
			(effects
				(font
					(size 1.27 1.27)
					(thickness 0.15)
				)
				(justify left bottom)
				(hide yes)
			)
		)
		(property "License" "Apache-2.0"
			(at 166.37 165.1 0)
			(effects
				(font
					(size 1.27 1.27)
					(thickness 0.15)
				)
				(justify left bottom)
				(hide yes)
			)
		)
		(property "Author" "Antmicro"
			(at 168.91 165.1 0)
			(effects
				(font
					(size 1.27 1.27)
					(thickness 0.15)
				)
				(justify left bottom)
				(hide yes)
			)
		)
		(property "Val" "2k2"
			(at 139.065 184.15 90)
			(effects
				(font
					(size 1.27 1.27)
					(thickness 0.15)
				)
				(justify left)
			)
		)
		(property "Tolerance" "1%"
			(at 151.13 165.1 0)
			(effects
				(font
					(size 1.27 1.27)
				)
				(justify left bottom)
				(hide yes)
			)
		)
		(property "Public" ""
			(at 171.45 165.1 0)
			(effects
				(font
					(size 1.27 1.27)
				)
				(justify left bottom)
				(hide yes)
			)
		)
		(pin "1"
		)
		(pin "2"
		)
		(instances
			(project "data-center-rdimm-ddr5-tester"
				(path ""
					(reference "R72")
					(unit 1)
				)
			)
		)
	)
	(symbol
		(lib_id "antmicroCapacitors0402:C_10u_10V_0402")
		(at 173.99 269.24 90)
		(unit 1)
		(exclude_from_sim no)
		(in_bom yes)
		(on_board yes)
		(dnp no)
		(property "Reference" "C284"
			(at 172.72 267.97 0)
			(effects
				(font
					(size 1.27 1.27)
					(thickness 0.15)
				)
				(justify right)
			)
		)
		(property "Value" "C_10u_10V_0402"
			(at 184.15 248.92 0)
			(effects
				(font
					(size 1.27 1.27)
					(thickness 0.15)
				)
				(justify left bottom)
				(hide yes)
			)
		)
		(property "Footprint" "antmicro-footprints:C_0402_1005Metric"
			(at 186.69 248.92 0)
			(effects
				(font
					(size 1.27 1.27)
					(thickness 0.15)
				)
				(justify left bottom)
				(hide yes)
			)
		)
		(property "Datasheet" "https://www.murata.com/products/productdetail?partno=GRM155R61A106ME11%23"
			(at 189.23 248.92 0)
			(effects
				(font
					(size 1.27 1.27)
					(thickness 0.15)
				)
				(justify left bottom)
				(hide yes)
			)
		)
		(property "Description" ""
			(at 173.99 269.24 0)
			(effects
				(font
					(size 1.27 1.27)
				)
				(hide yes)
			)
		)
		(property "MPN" "GRM155R61A106ME11D"
			(at 191.77 248.92 0)
			(effects
				(font
					(size 1.27 1.27)
					(thickness 0.15)
				)
				(justify left bottom)
				(hide yes)
			)
		)
		(property "Manufacturer" "Murata"
			(at 194.31 248.92 0)
			(effects
				(font
					(size 1.27 1.27)
					(thickness 0.15)
				)
				(justify left bottom)
				(hide yes)
			)
		)
		(property "License" "Apache-2.0"
			(at 196.85 248.92 0)
			(effects
				(font
					(size 1.27 1.27)
					(thickness 0.15)
				)
				(justify left bottom)
				(hide yes)
			)
		)
		(property "Author" "Antmicro"
			(at 199.39 248.92 0)
			(effects
				(font
					(size 1.27 1.27)
					(thickness 0.15)
				)
				(justify left bottom)
				(hide yes)
			)
		)
		(property "Val" "10u"
			(at 172.72 261.62 0)
			(effects
				(font
					(size 1.27 1.27)
					(thickness 0.15)
				)
				(justify right)
			)
		)
		(property "Voltage" "10V"
			(at 201.93 248.92 0)
			(effects
				(font
					(size 1.27 1.27)
				)
				(justify left bottom)
				(hide yes)
			)
		)
		(property "Dielectric" "X5R"
			(at 204.47 248.92 0)
			(effects
				(font
					(size 1.27 1.27)
				)
				(justify left bottom)
				(hide yes)
			)
		)
		(property "Public" ""
			(at 207.01 248.92 0)
			(effects
				(font
					(size 1.27 1.27)
				)
				(justify left bottom)
				(hide yes)
			)
		)
		(pin "1"
		)
		(pin "2"
		)
		(instances
			(project "data-center-rdimm-ddr5-tester"
				(path ""
					(reference "C284")
					(unit 1)
				)
			)
		)
	)
	(symbol
		(lib_id "antmicropower:GND")
		(at 349.25 246.38 0)
		(unit 1)
		(exclude_from_sim no)
		(in_bom yes)
		(on_board yes)
		(dnp no)
		(fields_autoplaced yes)
		(property "Reference" "#PWR0220"
			(at 349.25 252.73 0)
			(effects
				(font
					(size 1.27 1.27)
				)
				(hide yes)
			)
		)
		(property "Value" "GND"
			(at 347.345 250.825 0)
			(effects
				(font
					(size 1.27 1.27)
					(thickness 0.15)
				)
				(justify left bottom)
			)
		)
		(property "Footprint" ""
			(at 358.14 254 0)
			(effects
				(font
					(size 1.27 1.27)
					(thickness 0.15)
				)
				(justify left bottom)
				(hide yes)
			)
		)
		(property "Datasheet" ""
			(at 358.14 259.08 0)
			(effects
				(font
					(size 1.27 1.27)
					(thickness 0.15)
				)
				(justify left bottom)
				(hide yes)
			)
		)
		(property "Description" ""
			(at 349.25 246.38 0)
			(effects
				(font
					(size 1.27 1.27)
				)
				(hide yes)
			)
		)
		(property "Author" "Antmicro"
			(at 358.14 251.46 0)
			(effects
				(font
					(size 1.27 1.27)
					(thickness 0.15)
				)
				(justify left bottom)
				(hide yes)
			)
		)
		(property "License" "Apache-2.0"
			(at 358.14 254 0)
			(effects
				(font
					(size 1.27 1.27)
					(thickness 0.15)
				)
				(justify left bottom)
				(hide yes)
			)
		)
		(pin "1"
		)
		(instances
			(project "data-center-rdimm-ddr5-tester"
				(path ""
					(reference "#PWR0220")
					(unit 1)
				)
			)
		)
	)
	(symbol
		(lib_id "antmicropower:+5V")
		(at 163.83 210.82 0)
		(unit 1)
		(exclude_from_sim no)
		(in_bom yes)
		(on_board yes)
		(dnp no)
		(property "Reference" "#PWR0202"
			(at 163.83 214.63 0)
			(effects
				(font
					(size 1.27 1.27)
				)
				(hide yes)
			)
		)
		(property "Value" "+5V"
			(at 163.83 207.2456 0)
			(effects
				(font
					(size 1.27 1.27)
					(thickness 0.15)
				)
			)
		)
		(property "Footprint" ""
			(at 179.07 218.44 0)
			(effects
				(font
					(size 1.27 1.27)
					(thickness 0.15)
				)
				(justify left bottom)
				(hide yes)
			)
		)
		(property "Datasheet" ""
			(at 179.07 220.98 0)
			(effects
				(font
					(size 1.27 1.27)
					(thickness 0.15)
				)
				(justify left bottom)
				(hide yes)
			)
		)
		(property "Description" ""
			(at 163.83 210.82 0)
			(effects
				(font
					(size 1.27 1.27)
				)
				(hide yes)
			)
		)
		(property "Author" "Antmicro"
			(at 179.07 218.44 0)
			(effects
				(font
					(size 1.27 1.27)
					(thickness 0.15)
				)
				(justify left bottom)
				(hide yes)
			)
		)
		(property "License" "Apache-2.0"
			(at 179.07 220.98 0)
			(effects
				(font
					(size 1.27 1.27)
					(thickness 0.15)
				)
				(justify left bottom)
				(hide yes)
			)
		)
		(pin "1"
		)
		(instances
			(project "data-center-rdimm-ddr5-tester"
				(path ""
					(reference "#PWR0202")
					(unit 1)
				)
			)
		)
	)
	(symbol
		(lib_id "antmicroCapacitors0402:C_100n_0402")
		(at 311.15 39.37 270)
		(mirror x)
		(unit 1)
		(exclude_from_sim no)
		(in_bom yes)
		(on_board yes)
		(dnp no)
		(fields_autoplaced yes)
		(property "Reference" "C300"
			(at 313.69 35.5536 90)
			(effects
				(font
					(size 1.27 1.27)
				)
				(justify left)
			)
		)
		(property "Value" "C_100n_0402"
			(at 300.99 19.05 0)
			(effects
				(font
					(size 1.27 1.27)
					(thickness 0.15)
				)
				(justify left bottom)
				(hide yes)
			)
		)
		(property "Footprint" "antmicro-footprints:C_0402_1005Metric"
			(at 298.45 19.05 0)
			(effects
				(font
					(size 1.27 1.27)
					(thickness 0.15)
				)
				(justify left bottom)
				(hide yes)
			)
		)
		(property "Datasheet" "https://www.murata.com/products/productdetail?partno=GRM155R61H104KE14%23"
			(at 295.91 19.05 0)
			(effects
				(font
					(size 1.27 1.27)
					(thickness 0.15)
				)
				(justify left bottom)
				(hide yes)
			)
		)
		(property "Description" ""
			(at 311.15 39.37 0)
			(effects
				(font
					(size 1.27 1.27)
				)
				(hide yes)
			)
		)
		(property "Manufacturer" "Murata"
			(at 290.83 19.05 0)
			(effects
				(font
					(size 1.27 1.27)
					(thickness 0.15)
				)
				(justify left bottom)
				(hide yes)
			)
		)
		(property "MPN" "GRM155R61H104KE14D"
			(at 293.37 19.05 0)
			(effects
				(font
					(size 1.27 1.27)
					(thickness 0.15)
				)
				(justify left bottom)
				(hide yes)
			)
		)
		(property "Val" "100n"
			(at 313.69 38.0936 90)
			(effects
				(font
					(size 1.27 1.27)
					(thickness 0.15)
				)
				(justify left)
			)
		)
		(property "License" "Apache-2.0"
			(at 288.29 19.05 0)
			(effects
				(font
					(size 1.27 1.27)
					(thickness 0.15)
				)
				(justify left bottom)
				(hide yes)
			)
		)
		(property "Author" "Antmicro"
			(at 285.75 19.05 0)
			(effects
				(font
					(size 1.27 1.27)
					(thickness 0.15)
				)
				(justify left bottom)
				(hide yes)
			)
		)
		(property "Voltage" "50V"
			(at 283.21 19.05 0)
			(effects
				(font
					(size 1.27 1.27)
				)
				(justify left bottom)
				(hide yes)
			)
		)
		(property "Dielectric" "X5R"
			(at 280.67 19.05 0)
			(effects
				(font
					(size 1.27 1.27)
				)
				(justify left bottom)
				(hide yes)
			)
		)
		(pin "1"
		)
		(pin "2"
		)
		(instances
			(project "data-center-rdimm-ddr5-tester"
				(path ""
					(reference "C300")
					(unit 1)
				)
			)
		)
	)
	(symbol
		(lib_id "antmicropower:GND")
		(at 90.17 121.92 0)
		(unit 1)
		(exclude_from_sim no)
		(in_bom yes)
		(on_board yes)
		(dnp no)
		(property "Reference" "#PWR0478"
			(at 99.06 124.46 0)
			(effects
				(font
					(size 1.27 1.27)
					(thickness 0.15)
				)
				(justify left bottom)
				(hide yes)
			)
		)
		(property "Value" "GND"
			(at 90.17 125.73 0)
			(effects
				(font
					(size 1.27 1.27)
					(thickness 0.15)
				)
			)
		)
		(property "Footprint" ""
			(at 99.06 129.54 0)
			(effects
				(font
					(size 1.27 1.27)
					(thickness 0.15)
				)
				(justify left bottom)
				(hide yes)
			)
		)
		(property "Datasheet" ""
			(at 99.06 134.62 0)
			(effects
				(font
					(size 1.27 1.27)
					(thickness 0.15)
				)
				(justify left bottom)
				(hide yes)
			)
		)
		(property "Description" ""
			(at 90.17 121.92 0)
			(effects
				(font
					(size 1.27 1.27)
				)
				(hide yes)
			)
		)
		(property "Author" "Antmicro"
			(at 99.06 129.54 0)
			(effects
				(font
					(size 1.27 1.27)
					(thickness 0.15)
				)
				(justify left bottom)
				(hide yes)
			)
		)
		(property "License" "Apache-2.0"
			(at 99.06 132.08 0)
			(effects
				(font
					(size 1.27 1.27)
					(thickness 0.15)
				)
				(justify left bottom)
				(hide yes)
			)
		)
		(pin "1"
		)
		(instances
			(project "data-center-rdimm-ddr5-tester"
				(path ""
					(reference "#PWR0478")
					(unit 1)
				)
			)
		)
	)
	(symbol
		(lib_id "antmicroCapacitors0402:C_100n_0402")
		(at 288.29 160.02 270)
		(unit 1)
		(exclude_from_sim no)
		(in_bom yes)
		(on_board yes)
		(dnp no)
		(fields_autoplaced yes)
		(property "Reference" "C82"
			(at 290.83 161.2963 90)
			(effects
				(font
					(size 1.27 1.27)
					(thickness 0.15)
				)
				(justify left)
			)
		)
		(property "Value" "C_100n_0402"
			(at 278.13 180.34 0)
			(effects
				(font
					(size 1.27 1.27)
					(thickness 0.15)
				)
				(justify left bottom)
				(hide yes)
			)
		)
		(property "Footprint" "antmicro-footprints:C_0402_1005Metric"
			(at 275.59 180.34 0)
			(effects
				(font
					(size 1.27 1.27)
					(thickness 0.15)
				)
				(justify left bottom)
				(hide yes)
			)
		)
		(property "Datasheet" "https://www.murata.com/products/productdetail?partno=GRM155R61H104KE14%23"
			(at 273.05 180.34 0)
			(effects
				(font
					(size 1.27 1.27)
					(thickness 0.15)
				)
				(justify left bottom)
				(hide yes)
			)
		)
		(property "Description" ""
			(at 288.29 160.02 0)
			(effects
				(font
					(size 1.27 1.27)
				)
				(hide yes)
			)
		)
		(property "MPN" "GRM155R61H104KE14D"
			(at 270.51 180.34 0)
			(effects
				(font
					(size 1.27 1.27)
					(thickness 0.15)
				)
				(justify left bottom)
				(hide yes)
			)
		)
		(property "Manufacturer" "Murata"
			(at 267.97 180.34 0)
			(effects
				(font
					(size 1.27 1.27)
					(thickness 0.15)
				)
				(justify left bottom)
				(hide yes)
			)
		)
		(property "License" "Apache-2.0"
			(at 265.43 180.34 0)
			(effects
				(font
					(size 1.27 1.27)
					(thickness 0.15)
				)
				(justify left bottom)
				(hide yes)
			)
		)
		(property "Author" "Antmicro"
			(at 262.89 180.34 0)
			(effects
				(font
					(size 1.27 1.27)
					(thickness 0.15)
				)
				(justify left bottom)
				(hide yes)
			)
		)
		(property "Val" "100n"
			(at 290.83 163.8363 90)
			(effects
				(font
					(size 1.27 1.27)
					(thickness 0.15)
				)
				(justify left)
			)
		)
		(property "Voltage" "50V"
			(at 260.35 180.34 0)
			(effects
				(font
					(size 1.27 1.27)
				)
				(justify left bottom)
				(hide yes)
			)
		)
		(property "Dielectric" "X5R"
			(at 257.81 180.34 0)
			(effects
				(font
					(size 1.27 1.27)
				)
				(justify left bottom)
				(hide yes)
			)
		)
		(property "Public" ""
			(at 255.27 180.34 0)
			(effects
				(font
					(size 1.27 1.27)
				)
				(justify left bottom)
				(hide yes)
			)
		)
		(pin "2"
		)
		(pin "1"
		)
		(instances
			(project "data-center-rdimm-ddr5-tester"
				(path ""
					(reference "C82")
					(unit 1)
				)
			)
		)
	)
	(symbol
		(lib_id "antmicroCapacitors0402:C_100n_0402")
		(at 242.57 265.43 270)
		(unit 1)
		(exclude_from_sim no)
		(in_bom yes)
		(on_board yes)
		(dnp no)
		(property "Reference" "C29"
			(at 243.205 266.065 90)
			(effects
				(font
					(size 1.27 1.27)
					(thickness 0.15)
				)
				(justify left)
			)
		)
		(property "Value" "C_100n_0402"
			(at 232.41 285.75 0)
			(effects
				(font
					(size 1.27 1.27)
					(thickness 0.15)
				)
				(justify left bottom)
				(hide yes)
			)
		)
		(property "Footprint" "antmicro-footprints:C_0402_1005Metric"
			(at 229.87 285.75 0)
			(effects
				(font
					(size 1.27 1.27)
					(thickness 0.15)
				)
				(justify left bottom)
				(hide yes)
			)
		)
		(property "Datasheet" "https://www.murata.com/products/productdetail?partno=GRM155R61H104KE14%23"
			(at 227.33 285.75 0)
			(effects
				(font
					(size 1.27 1.27)
					(thickness 0.15)
				)
				(justify left bottom)
				(hide yes)
			)
		)
		(property "Description" ""
			(at 242.57 265.43 0)
			(effects
				(font
					(size 1.27 1.27)
				)
				(hide yes)
			)
		)
		(property "MPN" "GRM155R61H104KE14D"
			(at 224.79 285.75 0)
			(effects
				(font
					(size 1.27 1.27)
					(thickness 0.15)
				)
				(justify left bottom)
				(hide yes)
			)
		)
		(property "Manufacturer" "Murata"
			(at 222.25 285.75 0)
			(effects
				(font
					(size 1.27 1.27)
					(thickness 0.15)
				)
				(justify left bottom)
				(hide yes)
			)
		)
		(property "License" "Apache-2.0"
			(at 219.71 285.75 0)
			(effects
				(font
					(size 1.27 1.27)
					(thickness 0.15)
				)
				(justify left bottom)
				(hide yes)
			)
		)
		(property "Author" "Antmicro"
			(at 217.17 285.75 0)
			(effects
				(font
					(size 1.27 1.27)
					(thickness 0.15)
				)
				(justify left bottom)
				(hide yes)
			)
		)
		(property "Val" "100n"
			(at 243.205 269.875 90)
			(effects
				(font
					(size 1.27 1.27)
					(thickness 0.15)
				)
				(justify left)
			)
		)
		(property "Voltage" "50V"
			(at 214.63 285.75 0)
			(effects
				(font
					(size 1.27 1.27)
				)
				(justify left bottom)
				(hide yes)
			)
		)
		(property "Dielectric" "X5R"
			(at 212.09 285.75 0)
			(effects
				(font
					(size 1.27 1.27)
				)
				(justify left bottom)
				(hide yes)
			)
		)
		(property "Public" ""
			(at 209.55 285.75 0)
			(effects
				(font
					(size 1.27 1.27)
				)
				(justify left bottom)
				(hide yes)
			)
		)
		(pin "2"
		)
		(pin "1"
		)
		(instances
			(project "data-center-rdimm-ddr5-tester"
				(path ""
					(reference "C29")
					(unit 1)
				)
			)
		)
	)
	(symbol
		(lib_id "antmicroCapacitors0402:C_100n_0402")
		(at 387.35 161.29 270)
		(unit 1)
		(exclude_from_sim no)
		(in_bom yes)
		(on_board yes)
		(dnp no)
		(property "Reference" "C93"
			(at 387.985 161.925 90)
			(effects
				(font
					(size 1.27 1.27)
					(thickness 0.15)
				)
				(justify left)
			)
		)
		(property "Value" "C_100n_0402"
			(at 377.19 181.61 0)
			(effects
				(font
					(size 1.27 1.27)
					(thickness 0.15)
				)
				(justify left bottom)
				(hide yes)
			)
		)
		(property "Footprint" "antmicro-footprints:C_0402_1005Metric"
			(at 374.65 181.61 0)
			(effects
				(font
					(size 1.27 1.27)
					(thickness 0.15)
				)
				(justify left bottom)
				(hide yes)
			)
		)
		(property "Datasheet" "https://www.murata.com/products/productdetail?partno=GRM155R61H104KE14%23"
			(at 372.11 181.61 0)
			(effects
				(font
					(size 1.27 1.27)
					(thickness 0.15)
				)
				(justify left bottom)
				(hide yes)
			)
		)
		(property "Description" ""
			(at 387.35 161.29 0)
			(effects
				(font
					(size 1.27 1.27)
				)
				(hide yes)
			)
		)
		(property "MPN" "GRM155R61H104KE14D"
			(at 369.57 181.61 0)
			(effects
				(font
					(size 1.27 1.27)
					(thickness 0.15)
				)
				(justify left bottom)
				(hide yes)
			)
		)
		(property "Manufacturer" "Murata"
			(at 367.03 181.61 0)
			(effects
				(font
					(size 1.27 1.27)
					(thickness 0.15)
				)
				(justify left bottom)
				(hide yes)
			)
		)
		(property "License" "Apache-2.0"
			(at 364.49 181.61 0)
			(effects
				(font
					(size 1.27 1.27)
					(thickness 0.15)
				)
				(justify left bottom)
				(hide yes)
			)
		)
		(property "Author" "Antmicro"
			(at 361.95 181.61 0)
			(effects
				(font
					(size 1.27 1.27)
					(thickness 0.15)
				)
				(justify left bottom)
				(hide yes)
			)
		)
		(property "Val" "100n"
			(at 387.985 165.735 90)
			(effects
				(font
					(size 1.27 1.27)
					(thickness 0.15)
				)
				(justify left)
			)
		)
		(property "Voltage" "50V"
			(at 359.41 181.61 0)
			(effects
				(font
					(size 1.27 1.27)
				)
				(justify left bottom)
				(hide yes)
			)
		)
		(property "Dielectric" "X5R"
			(at 356.87 181.61 0)
			(effects
				(font
					(size 1.27 1.27)
				)
				(justify left bottom)
				(hide yes)
			)
		)
		(property "Public" ""
			(at 354.33 181.61 0)
			(effects
				(font
					(size 1.27 1.27)
				)
				(justify left bottom)
				(hide yes)
			)
		)
		(pin "2"
		)
		(pin "1"
		)
		(instances
			(project "data-center-rdimm-ddr5-tester"
				(path ""
					(reference "C93")
					(unit 1)
				)
			)
		)
	)
	(symbol
		(lib_id "antmicroResistors0402:R_49k9_0402")
		(at 361.95 38.1 90)
		(unit 1)
		(exclude_from_sim no)
		(in_bom yes)
		(on_board yes)
		(dnp no)
		(fields_autoplaced yes)
		(property "Reference" "R29"
			(at 363.855 34.29 90)
			(effects
				(font
					(size 1.27 1.27)
					(thickness 0.15)
				)
				(justify right)
			)
		)
		(property "Value" "R_49k9_0402"
			(at 374.65 17.78 0)
			(effects
				(font
					(size 1.27 1.27)
					(thickness 0.15)
				)
				(justify left bottom)
				(hide yes)
			)
		)
		(property "Footprint" "antmicro-footprints:R_0402_1005Metric"
			(at 377.19 17.78 0)
			(effects
				(font
					(size 1.27 1.27)
					(thickness 0.15)
				)
				(justify left bottom)
				(hide yes)
			)
		)
		(property "Datasheet" "https://www.bourns.com/docs/product-datasheets/cr.pdf"
			(at 379.73 17.78 0)
			(effects
				(font
					(size 1.27 1.27)
					(thickness 0.15)
				)
				(justify left bottom)
				(hide yes)
			)
		)
		(property "Description" ""
			(at 361.95 38.1 0)
			(effects
				(font
					(size 1.27 1.27)
				)
				(hide yes)
			)
		)
		(property "MPN" "CR0402-FX-4992GLF"
			(at 382.27 17.78 0)
			(effects
				(font
					(size 1.27 1.27)
					(thickness 0.15)
				)
				(justify left bottom)
				(hide yes)
			)
		)
		(property "Manufacturer" "Bourns"
			(at 384.81 17.78 0)
			(effects
				(font
					(size 1.27 1.27)
					(thickness 0.15)
				)
				(justify left bottom)
				(hide yes)
			)
		)
		(property "License" "Apache-2.0"
			(at 387.35 17.78 0)
			(effects
				(font
					(size 1.27 1.27)
					(thickness 0.15)
				)
				(justify left bottom)
				(hide yes)
			)
		)
		(property "Author" "Antmicro"
			(at 389.89 17.78 0)
			(effects
				(font
					(size 1.27 1.27)
					(thickness 0.15)
				)
				(justify left bottom)
				(hide yes)
			)
		)
		(property "Val" "49k9"
			(at 363.855 36.83 90)
			(effects
				(font
					(size 1.27 1.27)
					(thickness 0.15)
				)
				(justify right)
			)
		)
		(property "Tolerance" "1%"
			(at 372.11 17.78 0)
			(effects
				(font
					(size 1.27 1.27)
				)
				(justify left bottom)
				(hide yes)
			)
		)
		(pin "1"
		)
		(pin "2"
		)
		(instances
			(project "data-center-rdimm-ddr5-tester"
				(path ""
					(reference "R29")
					(unit 1)
				)
			)
		)
	)
	(symbol
		(lib_id "antmicroTransistorsFETsMOSFETsSingle:BSS138PW")
		(at 326.39 104.14 0)
		(unit 1)
		(exclude_from_sim no)
		(in_bom yes)
		(on_board yes)
		(dnp no)
		(property "Reference" "Q18"
			(at 337.82 100.33 0)
			(effects
				(font
					(size 1.27 1.27)
				)
				(justify left)
			)
		)
		(property "Value" "BSS138PW"
			(at 336.804 103.2997 0)
			(effects
				(font
					(size 1.27 1.27)
					(thickness 0.15)
				)
				(justify left)
				(hide yes)
			)
		)
		(property "Footprint" "antmicro-footprints:SC70-3"
			(at 349.25 115.57 0)
			(effects
				(font
					(size 1.27 1.27)
					(thickness 0.15)
				)
				(justify left bottom)
				(hide yes)
			)
		)
		(property "Datasheet" "https://assets.nexperia.com/documents/data-sheet/BSS138PW.pdf"
			(at 349.25 118.11 0)
			(effects
				(font
					(size 1.27 1.27)
					(thickness 0.15)
				)
				(justify left bottom)
				(hide yes)
			)
		)
		(property "Description" ""
			(at 326.39 104.14 0)
			(effects
				(font
					(size 1.27 1.27)
				)
				(hide yes)
			)
		)
		(property "MPN" "BSS138PW"
			(at 337.82 102.87 0)
			(effects
				(font
					(size 1.27 1.27)
					(thickness 0.15)
				)
				(justify left)
			)
		)
		(property "Manufacturer" "Nexperia"
			(at 349.25 123.19 0)
			(effects
				(font
					(size 1.27 1.27)
					(thickness 0.15)
				)
				(justify left bottom)
				(hide yes)
			)
		)
		(property "Author" "Antmicro"
			(at 349.25 125.73 0)
			(effects
				(font
					(size 1.27 1.27)
					(thickness 0.15)
				)
				(justify left bottom)
				(hide yes)
			)
		)
		(property "License" "Apache-2.0"
			(at 349.25 128.27 0)
			(effects
				(font
					(size 1.27 1.27)
					(thickness 0.15)
				)
				(justify left bottom)
				(hide yes)
			)
		)
		(pin "1"
		)
		(pin "2"
		)
		(pin "3"
		)
		(instances
			(project "data-center-rdimm-ddr5-tester"
				(path ""
					(reference "Q18")
					(unit 1)
				)
			)
		)
	)
	(symbol
		(lib_id "antmicroResistors0402:R_49k9_0402")
		(at 378.46 38.1 90)
		(unit 1)
		(exclude_from_sim no)
		(in_bom yes)
		(on_board yes)
		(dnp no)
		(fields_autoplaced yes)
		(property "Reference" "R28"
			(at 380.365 34.29 90)
			(effects
				(font
					(size 1.27 1.27)
					(thickness 0.15)
				)
				(justify right)
			)
		)
		(property "Value" "R_49k9_0402"
			(at 391.16 17.78 0)
			(effects
				(font
					(size 1.27 1.27)
					(thickness 0.15)
				)
				(justify left bottom)
				(hide yes)
			)
		)
		(property "Footprint" "antmicro-footprints:R_0402_1005Metric"
			(at 393.7 17.78 0)
			(effects
				(font
					(size 1.27 1.27)
					(thickness 0.15)
				)
				(justify left bottom)
				(hide yes)
			)
		)
		(property "Datasheet" "https://www.bourns.com/docs/product-datasheets/cr.pdf"
			(at 396.24 17.78 0)
			(effects
				(font
					(size 1.27 1.27)
					(thickness 0.15)
				)
				(justify left bottom)
				(hide yes)
			)
		)
		(property "Description" ""
			(at 378.46 38.1 0)
			(effects
				(font
					(size 1.27 1.27)
				)
				(hide yes)
			)
		)
		(property "MPN" "CR0402-FX-4992GLF"
			(at 398.78 17.78 0)
			(effects
				(font
					(size 1.27 1.27)
					(thickness 0.15)
				)
				(justify left bottom)
				(hide yes)
			)
		)
		(property "Manufacturer" "Bourns"
			(at 401.32 17.78 0)
			(effects
				(font
					(size 1.27 1.27)
					(thickness 0.15)
				)
				(justify left bottom)
				(hide yes)
			)
		)
		(property "License" "Apache-2.0"
			(at 403.86 17.78 0)
			(effects
				(font
					(size 1.27 1.27)
					(thickness 0.15)
				)
				(justify left bottom)
				(hide yes)
			)
		)
		(property "Author" "Antmicro"
			(at 406.4 17.78 0)
			(effects
				(font
					(size 1.27 1.27)
					(thickness 0.15)
				)
				(justify left bottom)
				(hide yes)
			)
		)
		(property "Val" "49k9"
			(at 380.365 36.83 90)
			(effects
				(font
					(size 1.27 1.27)
					(thickness 0.15)
				)
				(justify right)
			)
		)
		(property "Tolerance" "1%"
			(at 388.62 17.78 0)
			(effects
				(font
					(size 1.27 1.27)
				)
				(justify left bottom)
				(hide yes)
			)
		)
		(pin "1"
		)
		(pin "2"
		)
		(instances
			(project "data-center-rdimm-ddr5-tester"
				(path ""
					(reference "R28")
					(unit 1)
				)
			)
		)
	)
	(symbol
		(lib_id "antmicropower:+3V3")
		(at 21.59 107.95 0)
		(unit 1)
		(exclude_from_sim no)
		(in_bom yes)
		(on_board yes)
		(dnp no)
		(fields_autoplaced yes)
		(property "Reference" "#PWR0488"
			(at 36.83 107.95 0)
			(effects
				(font
					(size 1.27 1.27)
					(thickness 0.15)
				)
				(justify left bottom)
				(hide yes)
			)
		)
		(property "Value" "+3V3"
			(at 21.59 104.775 0)
			(effects
				(font
					(size 1.27 1.27)
					(thickness 0.15)
				)
			)
		)
		(property "Footprint" ""
			(at 36.83 115.57 0)
			(effects
				(font
					(size 1.27 1.27)
					(thickness 0.15)
				)
				(justify left bottom)
				(hide yes)
			)
		)
		(property "Datasheet" ""
			(at 36.83 118.11 0)
			(effects
				(font
					(size 1.27 1.27)
					(thickness 0.15)
				)
				(justify left bottom)
				(hide yes)
			)
		)
		(property "Description" ""
			(at 21.59 107.95 0)
			(effects
				(font
					(size 1.27 1.27)
				)
				(hide yes)
			)
		)
		(property "Author" "Antmicro"
			(at 36.83 110.49 0)
			(effects
				(font
					(size 1.27 1.27)
					(thickness 0.15)
				)
				(justify left bottom)
				(hide yes)
			)
		)
		(property "License" "Apache-2.0"
			(at 36.83 113.03 0)
			(effects
				(font
					(size 1.27 1.27)
					(thickness 0.15)
				)
				(justify left bottom)
				(hide yes)
			)
		)
		(pin "1"
		)
		(instances
			(project "data-center-rdimm-ddr5-tester"
				(path ""
					(reference "#PWR0488")
					(unit 1)
				)
			)
		)
	)
	(symbol
		(lib_id "antmicroResistors0402:R_64k9_0402")
		(at 39.37 264.16 180)
		(unit 1)
		(exclude_from_sim no)
		(in_bom no)
		(on_board yes)
		(dnp yes)
		(property "Reference" "R225"
			(at 39.37 262.89 0)
			(effects
				(font
					(size 1.27 1.27)
					(thickness 0.15)
				)
				(justify right)
			)
		)
		(property "Value" "R_64k9_0402"
			(at 19.05 251.46 0)
			(effects
				(font
					(size 1.27 1.27)
					(thickness 0.15)
				)
				(justify left bottom)
				(hide yes)
			)
		)
		(property "Footprint" "antmicro-footprints:R_0402_1005Metric"
			(at 19.05 248.92 0)
			(effects
				(font
					(size 1.27 1.27)
					(thickness 0.15)
				)
				(justify left bottom)
				(hide yes)
			)
		)
		(property "Datasheet" "https://www.bourns.com/docs/product-datasheets/cr.pdf"
			(at 19.05 246.38 0)
			(effects
				(font
					(size 1.27 1.27)
					(thickness 0.15)
				)
				(justify left bottom)
				(hide yes)
			)
		)
		(property "Description" ""
			(at 39.37 264.16 0)
			(effects
				(font
					(size 1.27 1.27)
				)
				(hide yes)
			)
		)
		(property "MPN" "CR0402-FX-6492GLF"
			(at 19.05 243.84 0)
			(effects
				(font
					(size 1.27 1.27)
					(thickness 0.15)
				)
				(justify left bottom)
				(hide yes)
			)
		)
		(property "Manufacturer" "Bourns"
			(at 19.05 241.3 0)
			(effects
				(font
					(size 1.27 1.27)
					(thickness 0.15)
				)
				(justify left bottom)
				(hide yes)
			)
		)
		(property "License" "Apache-2.0"
			(at 19.05 238.76 0)
			(effects
				(font
					(size 1.27 1.27)
					(thickness 0.15)
				)
				(justify left bottom)
				(hide yes)
			)
		)
		(property "Author" "Antmicro"
			(at 19.05 236.22 0)
			(effects
				(font
					(size 1.27 1.27)
					(thickness 0.15)
				)
				(justify left bottom)
				(hide yes)
			)
		)
		(property "Val" "64k9"
			(at 29.21 262.89 0)
			(effects
				(font
					(size 1.27 1.27)
					(thickness 0.15)
				)
				(justify right)
			)
		)
		(property "Tolerance" "1%"
			(at 19.05 254 0)
			(effects
				(font
					(size 1.27 1.27)
				)
				(justify left bottom)
				(hide yes)
			)
		)
		(pin "2"
		)
		(pin "1"
		)
		(instances
			(project "data-center-rdimm-ddr5-tester"
				(path ""
					(reference "R225")
					(unit 1)
				)
			)
		)
	)
	(symbol
		(lib_id "antmicropower:+1V8")
		(at 48.26 36.83 0)
		(unit 1)
		(exclude_from_sim no)
		(in_bom yes)
		(on_board yes)
		(dnp no)
		(fields_autoplaced yes)
		(property "Reference" "#PWR0483"
			(at 63.5 39.37 0)
			(effects
				(font
					(size 1.27 1.27)
					(thickness 0.15)
				)
				(justify left bottom)
				(hide yes)
			)
		)
		(property "Value" "+1V8"
			(at 48.26 33.02 0)
			(effects
				(font
					(size 1.27 1.27)
					(thickness 0.15)
				)
			)
		)
		(property "Footprint" ""
			(at 63.5 44.45 0)
			(effects
				(font
					(size 1.27 1.27)
					(thickness 0.15)
				)
				(justify left bottom)
				(hide yes)
			)
		)
		(property "Datasheet" ""
			(at 63.5 46.99 0)
			(effects
				(font
					(size 1.27 1.27)
					(thickness 0.15)
				)
				(justify left bottom)
				(hide yes)
			)
		)
		(property "Description" ""
			(at 48.26 36.83 0)
			(effects
				(font
					(size 1.27 1.27)
				)
				(hide yes)
			)
		)
		(property "Author" "Antmicro"
			(at 63.5 41.91 0)
			(effects
				(font
					(size 1.27 1.27)
					(thickness 0.15)
				)
				(justify left bottom)
				(hide yes)
			)
		)
		(property "License" "Apache-2.0"
			(at 63.5 44.45 0)
			(effects
				(font
					(size 1.27 1.27)
					(thickness 0.15)
				)
				(justify left bottom)
				(hide yes)
			)
		)
		(pin "1"
		)
		(instances
			(project "data-center-rdimm-ddr5-tester"
				(path ""
					(reference "#PWR0483")
					(unit 1)
				)
			)
		)
	)
	(symbol
		(lib_id "antmicroCapacitors0402:C_100n_0402")
		(at 19.05 44.45 90)
		(unit 1)
		(exclude_from_sim no)
		(in_bom yes)
		(on_board yes)
		(dnp no)
		(fields_autoplaced yes)
		(property "Reference" "C298"
			(at 22.86 40.6336 90)
			(effects
				(font
					(size 1.27 1.27)
					(thickness 0.15)
				)
				(justify right)
			)
		)
		(property "Value" "C_100n_0402"
			(at 29.21 24.13 0)
			(effects
				(font
					(size 1.27 1.27)
					(thickness 0.15)
				)
				(justify left bottom)
				(hide yes)
			)
		)
		(property "Footprint" "antmicro-footprints:C_0402_1005Metric"
			(at 31.75 24.13 0)
			(effects
				(font
					(size 1.27 1.27)
					(thickness 0.15)
				)
				(justify left bottom)
				(hide yes)
			)
		)
		(property "Datasheet" "https://www.murata.com/products/productdetail?partno=GRM155R61H104KE14%23"
			(at 34.29 24.13 0)
			(effects
				(font
					(size 1.27 1.27)
					(thickness 0.15)
				)
				(justify left bottom)
				(hide yes)
			)
		)
		(property "Description" ""
			(at 19.05 44.45 0)
			(effects
				(font
					(size 1.27 1.27)
				)
				(hide yes)
			)
		)
		(property "MPN" "GRM155R61H104KE14D"
			(at 36.83 24.13 0)
			(effects
				(font
					(size 1.27 1.27)
					(thickness 0.15)
				)
				(justify left bottom)
				(hide yes)
			)
		)
		(property "Manufacturer" "Murata"
			(at 39.37 24.13 0)
			(effects
				(font
					(size 1.27 1.27)
					(thickness 0.15)
				)
				(justify left bottom)
				(hide yes)
			)
		)
		(property "License" "Apache-2.0"
			(at 41.91 24.13 0)
			(effects
				(font
					(size 1.27 1.27)
					(thickness 0.15)
				)
				(justify left bottom)
				(hide yes)
			)
		)
		(property "Author" "Antmicro"
			(at 44.45 24.13 0)
			(effects
				(font
					(size 1.27 1.27)
					(thickness 0.15)
				)
				(justify left bottom)
				(hide yes)
			)
		)
		(property "Val" "100n"
			(at 22.86 43.1736 90)
			(effects
				(font
					(size 1.27 1.27)
					(thickness 0.15)
				)
				(justify right)
			)
		)
		(property "Voltage" "50V"
			(at 46.99 24.13 0)
			(effects
				(font
					(size 1.27 1.27)
				)
				(justify left bottom)
				(hide yes)
			)
		)
		(property "Dielectric" "X5R"
			(at 49.53 24.13 0)
			(effects
				(font
					(size 1.27 1.27)
				)
				(justify left bottom)
				(hide yes)
			)
		)
		(pin "1"
		)
		(pin "2"
		)
		(instances
			(project "data-center-rdimm-ddr5-tester"
				(path ""
					(reference "C298")
					(unit 1)
				)
			)
		)
	)
	(symbol
		(lib_id "antmicropower:GND")
		(at 359.41 171.45 0)
		(mirror y)
		(unit 1)
		(exclude_from_sim no)
		(in_bom yes)
		(on_board yes)
		(dnp no)
		(property "Reference" "#PWR0500"
			(at 359.41 177.8 0)
			(effects
				(font
					(size 1.27 1.27)
				)
				(hide yes)
			)
		)
		(property "Value" "GND"
			(at 359.41 175.26 0)
			(effects
				(font
					(size 1.27 1.27)
					(thickness 0.15)
				)
			)
		)
		(property "Footprint" ""
			(at 350.52 179.07 0)
			(effects
				(font
					(size 1.27 1.27)
					(thickness 0.15)
				)
				(justify left bottom)
				(hide yes)
			)
		)
		(property "Datasheet" ""
			(at 350.52 184.15 0)
			(effects
				(font
					(size 1.27 1.27)
					(thickness 0.15)
				)
				(justify left bottom)
				(hide yes)
			)
		)
		(property "Description" ""
			(at 359.41 171.45 0)
			(effects
				(font
					(size 1.27 1.27)
				)
				(hide yes)
			)
		)
		(property "Author" "Antmicro"
			(at 350.52 176.53 0)
			(effects
				(font
					(size 1.27 1.27)
					(thickness 0.15)
				)
				(justify left bottom)
				(hide yes)
			)
		)
		(property "License" "Apache-2.0"
			(at 350.52 179.07 0)
			(effects
				(font
					(size 1.27 1.27)
					(thickness 0.15)
				)
				(justify left bottom)
				(hide yes)
			)
		)
		(pin "1"
		)
		(instances
			(project "data-center-rdimm-ddr5-tester"
				(path ""
					(reference "#PWR0500")
					(unit 1)
				)
			)
		)
	)
	(symbol
		(lib_id "antmicroResistors0402:R_330R_0402")
		(at 180.34 85.09 0)
		(unit 1)
		(exclude_from_sim no)
		(in_bom yes)
		(on_board yes)
		(dnp no)
		(property "Reference" "R84"
			(at 182.88 88.265 0)
			(effects
				(font
					(size 1.27 1.27)
				)
			)
		)
		(property "Value" "R_330R_0402"
			(at 200.66 97.79 0)
			(effects
				(font
					(size 1.27 1.27)
					(thickness 0.15)
				)
				(justify left bottom)
				(hide yes)
			)
		)
		(property "Footprint" "antmicro-footprints:R_0402_1005Metric"
			(at 200.66 100.33 0)
			(effects
				(font
					(size 1.27 1.27)
					(thickness 0.15)
				)
				(justify left bottom)
				(hide yes)
			)
		)
		(property "Datasheet" "https://www.bourns.com/docs/product-datasheets/cr.pdf"
			(at 200.66 102.87 0)
			(effects
				(font
					(size 1.27 1.27)
					(thickness 0.15)
				)
				(justify left bottom)
				(hide yes)
			)
		)
		(property "Description" ""
			(at 180.34 85.09 0)
			(effects
				(font
					(size 1.27 1.27)
				)
				(hide yes)
			)
		)
		(property "Manufacturer" "Bourns"
			(at 200.66 107.95 0)
			(effects
				(font
					(size 1.27 1.27)
					(thickness 0.15)
				)
				(justify left bottom)
				(hide yes)
			)
		)
		(property "MPN" "CR0402-FX-3300GLF"
			(at 200.66 105.41 0)
			(effects
				(font
					(size 1.27 1.27)
					(thickness 0.15)
				)
				(justify left bottom)
				(hide yes)
			)
		)
		(property "Val" "330R"
			(at 182.88 90.805 0)
			(effects
				(font
					(size 1.27 1.27)
					(thickness 0.15)
				)
			)
		)
		(property "License" "Apache-2.0"
			(at 200.66 110.49 0)
			(effects
				(font
					(size 1.27 1.27)
					(thickness 0.15)
				)
				(justify left bottom)
				(hide yes)
			)
		)
		(property "Author" "Antmicro"
			(at 200.66 113.03 0)
			(effects
				(font
					(size 1.27 1.27)
					(thickness 0.15)
				)
				(justify left bottom)
				(hide yes)
			)
		)
		(property "Tolerance" "1%"
			(at 200.66 95.25 0)
			(effects
				(font
					(size 1.27 1.27)
				)
				(justify left bottom)
				(hide yes)
			)
		)
		(pin "1"
		)
		(pin "2"
		)
		(instances
			(project "data-center-rdimm-ddr5-tester"
				(path ""
					(reference "R84")
					(unit 1)
				)
			)
		)
	)
	(symbol
		(lib_id "antmicroResistors0402:R_64k9_0402")
		(at 71.12 269.24 180)
		(unit 1)
		(exclude_from_sim no)
		(in_bom yes)
		(on_board yes)
		(dnp no)
		(property "Reference" "R218"
			(at 71.12 267.97 0)
			(effects
				(font
					(size 1.27 1.27)
					(thickness 0.15)
				)
				(justify right)
			)
		)
		(property "Value" "R_64k9_0402"
			(at 50.8 256.54 0)
			(effects
				(font
					(size 1.27 1.27)
					(thickness 0.15)
				)
				(justify left bottom)
				(hide yes)
			)
		)
		(property "Footprint" "antmicro-footprints:R_0402_1005Metric"
			(at 50.8 254 0)
			(effects
				(font
					(size 1.27 1.27)
					(thickness 0.15)
				)
				(justify left bottom)
				(hide yes)
			)
		)
		(property "Datasheet" "https://www.bourns.com/docs/product-datasheets/cr.pdf"
			(at 50.8 251.46 0)
			(effects
				(font
					(size 1.27 1.27)
					(thickness 0.15)
				)
				(justify left bottom)
				(hide yes)
			)
		)
		(property "Description" ""
			(at 71.12 269.24 0)
			(effects
				(font
					(size 1.27 1.27)
				)
				(hide yes)
			)
		)
		(property "MPN" "CR0402-FX-6492GLF"
			(at 50.8 248.92 0)
			(effects
				(font
					(size 1.27 1.27)
					(thickness 0.15)
				)
				(justify left bottom)
				(hide yes)
			)
		)
		(property "Manufacturer" "Bourns"
			(at 50.8 246.38 0)
			(effects
				(font
					(size 1.27 1.27)
					(thickness 0.15)
				)
				(justify left bottom)
				(hide yes)
			)
		)
		(property "License" "Apache-2.0"
			(at 50.8 243.84 0)
			(effects
				(font
					(size 1.27 1.27)
					(thickness 0.15)
				)
				(justify left bottom)
				(hide yes)
			)
		)
		(property "Author" "Antmicro"
			(at 50.8 241.3 0)
			(effects
				(font
					(size 1.27 1.27)
					(thickness 0.15)
				)
				(justify left bottom)
				(hide yes)
			)
		)
		(property "Val" "64k9"
			(at 60.96 267.97 0)
			(effects
				(font
					(size 1.27 1.27)
					(thickness 0.15)
				)
				(justify right)
			)
		)
		(property "Tolerance" "1%"
			(at 50.8 259.08 0)
			(effects
				(font
					(size 1.27 1.27)
				)
				(justify left bottom)
				(hide yes)
			)
		)
		(pin "2"
		)
		(pin "1"
		)
		(instances
			(project "data-center-rdimm-ddr5-tester"
				(path ""
					(reference "R218")
					(unit 1)
				)
			)
		)
	)
	(symbol
		(lib_id "antmicroFixedInductors:L_20n_0.35A_0402")
		(at 353.06 45.72 90)
		(unit 1)
		(exclude_from_sim no)
		(in_bom yes)
		(on_board yes)
		(dnp no)
		(property "Reference" "L10"
			(at 354.33 41.91 90)
			(effects
				(font
					(size 1.27 1.27)
					(thickness 0.15)
				)
				(justify right)
			)
		)
		(property "Value" "L_20n_0.35A_0402"
			(at 355.6 31.75 0)
			(effects
				(font
					(size 1.27 1.27)
					(thickness 0.15)
				)
				(justify left bottom)
				(hide yes)
			)
		)
		(property "Footprint" "antmicro-footprints:L_0402_1005Metric"
			(at 360.68 31.75 0)
			(effects
				(font
					(size 1.27 1.27)
					(thickness 0.15)
				)
				(justify left bottom)
				(hide yes)
			)
		)
		(property "Datasheet" "https://product.tdk.com/system/files/dam/doc/product/inductor/inductor/smd/catalog/inductor_automotive_high-frequency_mlg1005s_en.pdf?ref_disty=mouser"
			(at 363.22 31.75 0)
			(effects
				(font
					(size 1.27 1.27)
					(thickness 0.15)
				)
				(justify left bottom)
				(hide yes)
			)
		)
		(property "Description" ""
			(at 353.06 45.72 0)
			(effects
				(font
					(size 1.27 1.27)
				)
				(hide yes)
			)
		)
		(property "Val" "20n/0.35A"
			(at 350.52 40.005 0)
			(effects
				(font
					(size 1.27 1.27)
					(thickness 0.15)
				)
				(justify right)
			)
		)
		(property "Manufacturer" "TDK"
			(at 365.76 31.75 0)
			(effects
				(font
					(size 1.27 1.27)
					(thickness 0.15)
				)
				(justify left bottom)
				(hide yes)
			)
		)
		(property "MPN" "MLG1005S20NJTD25"
			(at 368.3 31.75 0)
			(effects
				(font
					(size 1.27 1.27)
					(thickness 0.15)
				)
				(justify left bottom)
				(hide yes)
			)
		)
		(property "ISat" ""
			(at 369.57 31.75 0)
			(effects
				(font
					(size 1.27 1.27)
				)
				(justify left)
				(hide yes)
			)
		)
		(property "IMax" "0.35 A"
			(at 373.38 31.75 0)
			(effects
				(font
					(size 1.27 1.27)
					(thickness 0.15)
				)
				(justify left bottom)
				(hide yes)
			)
		)
		(property "Size" "1.0x0.5"
			(at 375.92 31.75 0)
			(effects
				(font
					(size 1.27 1.27)
					(thickness 0.15)
				)
				(justify left bottom)
				(hide yes)
			)
		)
		(property "Author" "Antmicro"
			(at 378.46 31.75 0)
			(effects
				(font
					(size 1.27 1.27)
					(thickness 0.15)
				)
				(justify left bottom)
				(hide yes)
			)
		)
		(property "License" "Apache-2.0"
			(at 381 31.75 0)
			(effects
				(font
					(size 1.27 1.27)
					(thickness 0.15)
				)
				(justify left bottom)
				(hide yes)
			)
		)
		(pin "2"
		)
		(pin "1"
		)
		(instances
			(project "data-center-rdimm-ddr5-tester"
				(path ""
					(reference "L10")
					(unit 1)
				)
			)
		)
	)
	(symbol
		(lib_id "antmicropower:GND")
		(at 311.15 40.64 0)
		(mirror y)
		(unit 1)
		(exclude_from_sim no)
		(in_bom yes)
		(on_board yes)
		(dnp no)
		(fields_autoplaced yes)
		(property "Reference" "#PWR0214"
			(at 311.15 46.99 0)
			(effects
				(font
					(size 1.27 1.27)
				)
				(hide yes)
			)
		)
		(property "Value" "GND"
			(at 313.055 45.085 0)
			(effects
				(font
					(size 1.27 1.27)
					(thickness 0.15)
				)
				(justify left bottom)
			)
		)
		(property "Footprint" ""
			(at 302.26 48.26 0)
			(effects
				(font
					(size 1.27 1.27)
					(thickness 0.15)
				)
				(justify left bottom)
				(hide yes)
			)
		)
		(property "Datasheet" ""
			(at 302.26 53.34 0)
			(effects
				(font
					(size 1.27 1.27)
					(thickness 0.15)
				)
				(justify left bottom)
				(hide yes)
			)
		)
		(property "Description" ""
			(at 311.15 40.64 0)
			(effects
				(font
					(size 1.27 1.27)
				)
				(hide yes)
			)
		)
		(property "Author" "Antmicro"
			(at 302.26 45.72 0)
			(effects
				(font
					(size 1.27 1.27)
					(thickness 0.15)
				)
				(justify left bottom)
				(hide yes)
			)
		)
		(property "License" "Apache-2.0"
			(at 302.26 48.26 0)
			(effects
				(font
					(size 1.27 1.27)
					(thickness 0.15)
				)
				(justify left bottom)
				(hide yes)
			)
		)
		(pin "1"
		)
		(instances
			(project "data-center-rdimm-ddr5-tester"
				(path ""
					(reference "#PWR0214")
					(unit 1)
				)
			)
		)
	)
	(symbol
		(lib_id "antmicroLogicTranslatorsLevelShifters:NVT4858_XQFN")
		(at 64.77 40.64 0)
		(unit 1)
		(exclude_from_sim no)
		(in_bom yes)
		(on_board yes)
		(dnp no)
		(fields_autoplaced yes)
		(property "Reference" "U40"
			(at 74.295 33.02 0)
			(effects
				(font
					(size 1.27 1.27)
					(thickness 0.15)
				)
			)
		)
		(property "Value" "NVT4858_XQFN"
			(at 118.11 45.72 0)
			(effects
				(font
					(size 1.27 1.27)
					(thickness 0.15)
				)
				(justify left bottom)
				(hide yes)
			)
		)
		(property "Footprint" "antmicro-footprints:SOT1161-2"
			(at 118.11 48.26 0)
			(effects
				(font
					(size 1.27 1.27)
					(thickness 0.15)
				)
				(justify left bottom)
				(hide yes)
			)
		)
		(property "Datasheet" "https://www.nxp.com/docs/en/data-sheet/NVT4858DS.pdf"
			(at 118.11 50.8 0)
			(effects
				(font
					(size 1.27 1.27)
					(thickness 0.15)
				)
				(justify left bottom)
				(hide yes)
			)
		)
		(property "Description" ""
			(at 64.77 40.64 0)
			(effects
				(font
					(size 1.27 1.27)
				)
				(hide yes)
			)
		)
		(property "Manufacturer" "NXP"
			(at 118.11 53.34 0)
			(effects
				(font
					(size 1.27 1.27)
					(thickness 0.15)
				)
				(justify left bottom)
				(hide yes)
			)
		)
		(property "MPN" "NVT4858HKZ"
			(at 74.295 35.56 0)
			(effects
				(font
					(size 1.27 1.27)
					(thickness 0.15)
				)
			)
		)
		(property "Author" "Antmicro"
			(at 118.11 58.42 0)
			(effects
				(font
					(size 1.27 1.27)
					(thickness 0.15)
				)
				(justify left bottom)
				(hide yes)
			)
		)
		(property "License" "Apache-2.0"
			(at 118.11 60.96 0)
			(effects
				(font
					(size 1.27 1.27)
					(thickness 0.15)
				)
				(justify left bottom)
				(hide yes)
			)
		)
		(pin "8"
		)
		(pin "7"
		)
		(pin "16"
		)
		(pin "10"
		)
		(pin "11"
		)
		(pin "12"
		)
		(pin "13"
		)
		(pin "14"
		)
		(pin "15"
		)
		(pin "4"
		)
		(pin "6"
		)
		(pin "5"
		)
		(pin "9"
		)
		(pin "1"
		)
		(pin "2"
		)
		(pin "3"
		)
		(instances
			(project "data-center-rdimm-ddr5-tester"
				(path ""
					(reference "U40")
					(unit 1)
				)
			)
		)
	)
	(symbol
		(lib_id "antmicroResistors0402:R_2k2_0402")
		(at 49.53 180.34 90)
		(unit 1)
		(exclude_from_sim no)
		(in_bom yes)
		(on_board yes)
		(dnp no)
		(property "Reference" "R239"
			(at 50.927 175.641 0)
			(effects
				(font
					(size 1.27 1.27)
					(thickness 0.15)
				)
				(justify left)
			)
		)
		(property "Value" "R_2k2_0402"
			(at 62.23 160.02 0)
			(effects
				(font
					(size 1.27 1.27)
					(thickness 0.15)
				)
				(justify left bottom)
				(hide yes)
			)
		)
		(property "Footprint" "antmicro-footprints:R_0402_1005Metric"
			(at 64.77 160.02 0)
			(effects
				(font
					(size 1.27 1.27)
					(thickness 0.15)
				)
				(justify left bottom)
				(hide yes)
			)
		)
		(property "Datasheet" "https://www.bourns.com/docs/product-datasheets/cr.pdf"
			(at 67.31 160.02 0)
			(effects
				(font
					(size 1.27 1.27)
					(thickness 0.15)
				)
				(justify left bottom)
				(hide yes)
			)
		)
		(property "Description" ""
			(at 49.53 180.34 0)
			(effects
				(font
					(size 1.27 1.27)
				)
				(hide yes)
			)
		)
		(property "MPN" "CR0402-FX-2201GLF"
			(at 69.85 160.02 0)
			(effects
				(font
					(size 1.27 1.27)
					(thickness 0.15)
				)
				(justify left bottom)
				(hide yes)
			)
		)
		(property "Manufacturer" "Bourns"
			(at 72.39 160.02 0)
			(effects
				(font
					(size 1.27 1.27)
					(thickness 0.15)
				)
				(justify left bottom)
				(hide yes)
			)
		)
		(property "License" "Apache-2.0"
			(at 74.93 160.02 0)
			(effects
				(font
					(size 1.27 1.27)
					(thickness 0.15)
				)
				(justify left bottom)
				(hide yes)
			)
		)
		(property "Author" "Antmicro"
			(at 77.47 160.02 0)
			(effects
				(font
					(size 1.27 1.27)
					(thickness 0.15)
				)
				(justify left bottom)
				(hide yes)
			)
		)
		(property "Val" "2k2"
			(at 51.054 183.642 0)
			(effects
				(font
					(size 1.27 1.27)
					(thickness 0.15)
				)
				(justify left)
			)
		)
		(property "Tolerance" "1%"
			(at 59.69 160.02 0)
			(effects
				(font
					(size 1.27 1.27)
				)
				(justify left bottom)
				(hide yes)
			)
		)
		(property "Public" ""
			(at 80.01 160.02 0)
			(effects
				(font
					(size 1.27 1.27)
				)
				(justify left bottom)
				(hide yes)
			)
		)
		(pin "1"
		)
		(pin "2"
		)
		(instances
			(project "data-center-rdimm-ddr5-tester"
				(path ""
					(reference "R239")
					(unit 1)
				)
			)
		)
	)
	(symbol
		(lib_id "antmicropower:+3V3")
		(at 288.29 158.75 0)
		(unit 1)
		(exclude_from_sim no)
		(in_bom yes)
		(on_board yes)
		(dnp no)
		(fields_autoplaced yes)
		(property "Reference" "#PWR0501"
			(at 303.53 158.75 0)
			(effects
				(font
					(size 1.27 1.27)
					(thickness 0.15)
				)
				(justify left bottom)
				(hide yes)
			)
		)
		(property "Value" "+3V3"
			(at 288.29 153.67 0)
			(effects
				(font
					(size 1.27 1.27)
					(thickness 0.15)
				)
			)
		)
		(property "Footprint" ""
			(at 303.53 166.37 0)
			(effects
				(font
					(size 1.27 1.27)
					(thickness 0.15)
				)
				(justify left bottom)
				(hide yes)
			)
		)
		(property "Datasheet" ""
			(at 303.53 168.91 0)
			(effects
				(font
					(size 1.27 1.27)
					(thickness 0.15)
				)
				(justify left bottom)
				(hide yes)
			)
		)
		(property "Description" ""
			(at 288.29 158.75 0)
			(effects
				(font
					(size 1.27 1.27)
				)
				(hide yes)
			)
		)
		(property "Author" "Antmicro"
			(at 303.53 161.29 0)
			(effects
				(font
					(size 1.27 1.27)
					(thickness 0.15)
				)
				(justify left bottom)
				(hide yes)
			)
		)
		(property "License" "Apache-2.0"
			(at 303.53 163.83 0)
			(effects
				(font
					(size 1.27 1.27)
					(thickness 0.15)
				)
				(justify left bottom)
				(hide yes)
			)
		)
		(pin "1"
		)
		(instances
			(project "data-center-rdimm-ddr5-tester"
				(path ""
					(reference "#PWR0501")
					(unit 1)
				)
			)
		)
	)
	(symbol
		(lib_id "antmicropower:GND")
		(at 67.31 234.95 0)
		(unit 1)
		(exclude_from_sim no)
		(in_bom yes)
		(on_board yes)
		(dnp no)
		(fields_autoplaced yes)
		(property "Reference" "#PWR0475"
			(at 76.2 237.49 0)
			(effects
				(font
					(size 1.27 1.27)
					(thickness 0.15)
				)
				(justify left bottom)
				(hide yes)
			)
		)
		(property "Value" "GND"
			(at 67.31 239.395 0)
			(effects
				(font
					(size 1.27 1.27)
					(thickness 0.15)
				)
			)
		)
		(property "Footprint" ""
			(at 76.2 242.57 0)
			(effects
				(font
					(size 1.27 1.27)
					(thickness 0.15)
				)
				(justify left bottom)
				(hide yes)
			)
		)
		(property "Datasheet" ""
			(at 76.2 247.65 0)
			(effects
				(font
					(size 1.27 1.27)
					(thickness 0.15)
				)
				(justify left bottom)
				(hide yes)
			)
		)
		(property "Description" ""
			(at 67.31 234.95 0)
			(effects
				(font
					(size 1.27 1.27)
				)
				(hide yes)
			)
		)
		(property "Author" "Antmicro"
			(at 76.2 242.57 0)
			(effects
				(font
					(size 1.27 1.27)
					(thickness 0.15)
				)
				(justify left bottom)
				(hide yes)
			)
		)
		(property "License" "Apache-2.0"
			(at 76.2 245.11 0)
			(effects
				(font
					(size 1.27 1.27)
					(thickness 0.15)
				)
				(justify left bottom)
				(hide yes)
			)
		)
		(pin "1"
		)
		(instances
			(project "data-center-rdimm-ddr5-tester"
				(path ""
					(reference "#PWR0475")
					(unit 1)
				)
			)
		)
	)
	(symbol
		(lib_id "antmicroCapacitors0402:C_100n_0402")
		(at 57.15 228.6 270)
		(unit 1)
		(exclude_from_sim no)
		(in_bom no)
		(on_board yes)
		(dnp yes)
		(fields_autoplaced yes)
		(property "Reference" "C294"
			(at 60.325 228.6063 90)
			(effects
				(font
					(size 1.27 1.27)
					(thickness 0.15)
				)
				(justify left)
			)
		)
		(property "Value" "C_100n_0402"
			(at 46.99 248.92 0)
			(effects
				(font
					(size 1.27 1.27)
					(thickness 0.15)
				)
				(justify left bottom)
				(hide yes)
			)
		)
		(property "Footprint" "antmicro-footprints:C_0402_1005Metric"
			(at 44.45 248.92 0)
			(effects
				(font
					(size 1.27 1.27)
					(thickness 0.15)
				)
				(justify left bottom)
				(hide yes)
			)
		)
		(property "Datasheet" "https://www.murata.com/products/productdetail?partno=GRM155R61H104KE14%23"
			(at 41.91 248.92 0)
			(effects
				(font
					(size 1.27 1.27)
					(thickness 0.15)
				)
				(justify left bottom)
				(hide yes)
			)
		)
		(property "Description" ""
			(at 57.15 228.6 0)
			(effects
				(font
					(size 1.27 1.27)
				)
				(hide yes)
			)
		)
		(property "MPN" "GRM155R61H104KE14D"
			(at 39.37 248.92 0)
			(effects
				(font
					(size 1.27 1.27)
					(thickness 0.15)
				)
				(justify left bottom)
				(hide yes)
			)
		)
		(property "Manufacturer" "Murata"
			(at 36.83 248.92 0)
			(effects
				(font
					(size 1.27 1.27)
					(thickness 0.15)
				)
				(justify left bottom)
				(hide yes)
			)
		)
		(property "License" "Apache-2.0"
			(at 34.29 248.92 0)
			(effects
				(font
					(size 1.27 1.27)
					(thickness 0.15)
				)
				(justify left bottom)
				(hide yes)
			)
		)
		(property "Author" "Antmicro"
			(at 31.75 248.92 0)
			(effects
				(font
					(size 1.27 1.27)
					(thickness 0.15)
				)
				(justify left bottom)
				(hide yes)
			)
		)
		(property "Val" "100n"
			(at 60.325 231.1463 90)
			(effects
				(font
					(size 1.27 1.27)
					(thickness 0.15)
				)
				(justify left)
			)
		)
		(property "Voltage" "50V"
			(at 29.21 248.92 0)
			(effects
				(font
					(size 1.27 1.27)
				)
				(justify left bottom)
				(hide yes)
			)
		)
		(property "Dielectric" "X5R"
			(at 26.67 248.92 0)
			(effects
				(font
					(size 1.27 1.27)
				)
				(justify left bottom)
				(hide yes)
			)
		)
		(property "Public" ""
			(at 24.13 248.92 0)
			(effects
				(font
					(size 1.27 1.27)
				)
				(justify left bottom)
				(hide yes)
			)
		)
		(pin "2"
		)
		(pin "1"
		)
		(instances
			(project "data-center-rdimm-ddr5-tester"
				(path ""
					(reference "C294")
					(unit 1)
				)
			)
		)
	)
	(symbol
		(lib_id "antmicroResistors0402:R_10k_0402")
		(at 365.76 133.35 90)
		(unit 1)
		(exclude_from_sim no)
		(in_bom yes)
		(on_board yes)
		(dnp no)
		(fields_autoplaced yes)
		(property "Reference" "R85"
			(at 368.3 129.54 90)
			(effects
				(font
					(size 1.27 1.27)
					(thickness 0.15)
				)
				(justify right)
			)
		)
		(property "Value" "R_10k_0402"
			(at 378.46 113.03 0)
			(effects
				(font
					(size 1.27 1.27)
					(thickness 0.15)
				)
				(justify left bottom)
				(hide yes)
			)
		)
		(property "Footprint" "antmicro-footprints:R_0402_1005Metric"
			(at 381 113.03 0)
			(effects
				(font
					(size 1.27 1.27)
					(thickness 0.15)
				)
				(justify left bottom)
				(hide yes)
			)
		)
		(property "Datasheet" "https://www.bourns.com/docs/product-datasheets/cr.pdf"
			(at 383.54 113.03 0)
			(effects
				(font
					(size 1.27 1.27)
					(thickness 0.15)
				)
				(justify left bottom)
				(hide yes)
			)
		)
		(property "Description" ""
			(at 365.76 133.35 0)
			(effects
				(font
					(size 1.27 1.27)
				)
				(hide yes)
			)
		)
		(property "MPN" "CR0402-FX-1002GLF"
			(at 386.08 113.03 0)
			(effects
				(font
					(size 1.27 1.27)
					(thickness 0.15)
				)
				(justify left bottom)
				(hide yes)
			)
		)
		(property "Manufacturer" "Bourns"
			(at 388.62 113.03 0)
			(effects
				(font
					(size 1.27 1.27)
					(thickness 0.15)
				)
				(justify left bottom)
				(hide yes)
			)
		)
		(property "License" "Apache-2.0"
			(at 391.16 113.03 0)
			(effects
				(font
					(size 1.27 1.27)
					(thickness 0.15)
				)
				(justify left bottom)
				(hide yes)
			)
		)
		(property "Author" "Antmicro"
			(at 393.7 113.03 0)
			(effects
				(font
					(size 1.27 1.27)
					(thickness 0.15)
				)
				(justify left bottom)
				(hide yes)
			)
		)
		(property "Val" "10k"
			(at 368.3 132.08 90)
			(effects
				(font
					(size 1.27 1.27)
					(thickness 0.15)
				)
				(justify right)
			)
		)
		(property "Tolerance" "1%"
			(at 375.92 113.03 0)
			(effects
				(font
					(size 1.27 1.27)
				)
				(justify left bottom)
				(hide yes)
			)
		)
		(pin "1"
		)
		(pin "2"
		)
		(instances
			(project "data-center-rdimm-ddr5-tester"
				(path ""
					(reference "R85")
					(unit 1)
				)
			)
		)
	)
	(symbol
		(lib_id "antmicroResistors0402:R_64k9_0402")
		(at 39.37 266.7 180)
		(unit 1)
		(exclude_from_sim no)
		(in_bom no)
		(on_board yes)
		(dnp yes)
		(property "Reference" "R226"
			(at 39.37 265.43 0)
			(effects
				(font
					(size 1.27 1.27)
					(thickness 0.15)
				)
				(justify right)
			)
		)
		(property "Value" "R_64k9_0402"
			(at 19.05 254 0)
			(effects
				(font
					(size 1.27 1.27)
					(thickness 0.15)
				)
				(justify left bottom)
				(hide yes)
			)
		)
		(property "Footprint" "antmicro-footprints:R_0402_1005Metric"
			(at 19.05 251.46 0)
			(effects
				(font
					(size 1.27 1.27)
					(thickness 0.15)
				)
				(justify left bottom)
				(hide yes)
			)
		)
		(property "Datasheet" "https://www.bourns.com/docs/product-datasheets/cr.pdf"
			(at 19.05 248.92 0)
			(effects
				(font
					(size 1.27 1.27)
					(thickness 0.15)
				)
				(justify left bottom)
				(hide yes)
			)
		)
		(property "Description" ""
			(at 39.37 266.7 0)
			(effects
				(font
					(size 1.27 1.27)
				)
				(hide yes)
			)
		)
		(property "MPN" "CR0402-FX-6492GLF"
			(at 19.05 246.38 0)
			(effects
				(font
					(size 1.27 1.27)
					(thickness 0.15)
				)
				(justify left bottom)
				(hide yes)
			)
		)
		(property "Manufacturer" "Bourns"
			(at 19.05 243.84 0)
			(effects
				(font
					(size 1.27 1.27)
					(thickness 0.15)
				)
				(justify left bottom)
				(hide yes)
			)
		)
		(property "License" "Apache-2.0"
			(at 19.05 241.3 0)
			(effects
				(font
					(size 1.27 1.27)
					(thickness 0.15)
				)
				(justify left bottom)
				(hide yes)
			)
		)
		(property "Author" "Antmicro"
			(at 19.05 238.76 0)
			(effects
				(font
					(size 1.27 1.27)
					(thickness 0.15)
				)
				(justify left bottom)
				(hide yes)
			)
		)
		(property "Val" "64k9"
			(at 29.21 265.43 0)
			(effects
				(font
					(size 1.27 1.27)
					(thickness 0.15)
				)
				(justify right)
			)
		)
		(property "Tolerance" "1%"
			(at 19.05 256.54 0)
			(effects
				(font
					(size 1.27 1.27)
				)
				(justify left bottom)
				(hide yes)
			)
		)
		(pin "2"
		)
		(pin "1"
		)
		(instances
			(project "data-center-rdimm-ddr5-tester"
				(path ""
					(reference "R226")
					(unit 1)
				)
			)
		)
	)
	(symbol
		(lib_id "antmicroFixedInductors:L_20n_0.35A_0402")
		(at 361.95 45.72 90)
		(unit 1)
		(exclude_from_sim no)
		(in_bom yes)
		(on_board yes)
		(dnp no)
		(property "Reference" "L5"
			(at 363.22 41.91 90)
			(effects
				(font
					(size 1.27 1.27)
					(thickness 0.15)
				)
				(justify right)
			)
		)
		(property "Value" "L_20n_0.35A_0402"
			(at 364.49 31.75 0)
			(effects
				(font
					(size 1.27 1.27)
					(thickness 0.15)
				)
				(justify left bottom)
				(hide yes)
			)
		)
		(property "Footprint" "antmicro-footprints:L_0402_1005Metric"
			(at 369.57 31.75 0)
			(effects
				(font
					(size 1.27 1.27)
					(thickness 0.15)
				)
				(justify left bottom)
				(hide yes)
			)
		)
		(property "Datasheet" "https://product.tdk.com/system/files/dam/doc/product/inductor/inductor/smd/catalog/inductor_automotive_high-frequency_mlg1005s_en.pdf?ref_disty=mouser"
			(at 372.11 31.75 0)
			(effects
				(font
					(size 1.27 1.27)
					(thickness 0.15)
				)
				(justify left bottom)
				(hide yes)
			)
		)
		(property "Description" ""
			(at 361.95 45.72 0)
			(effects
				(font
					(size 1.27 1.27)
				)
				(hide yes)
			)
		)
		(property "Val" "20n/0.35A"
			(at 359.41 40.005 0)
			(effects
				(font
					(size 1.27 1.27)
					(thickness 0.15)
				)
				(justify right)
			)
		)
		(property "Manufacturer" "TDK"
			(at 374.65 31.75 0)
			(effects
				(font
					(size 1.27 1.27)
					(thickness 0.15)
				)
				(justify left bottom)
				(hide yes)
			)
		)
		(property "MPN" "MLG1005S20NJTD25"
			(at 377.19 31.75 0)
			(effects
				(font
					(size 1.27 1.27)
					(thickness 0.15)
				)
				(justify left bottom)
				(hide yes)
			)
		)
		(property "ISat" ""
			(at 378.46 31.75 0)
			(effects
				(font
					(size 1.27 1.27)
				)
				(justify left)
				(hide yes)
			)
		)
		(property "IMax" "0.35 A"
			(at 382.27 31.75 0)
			(effects
				(font
					(size 1.27 1.27)
					(thickness 0.15)
				)
				(justify left bottom)
				(hide yes)
			)
		)
		(property "Size" "1.0x0.5"
			(at 384.81 31.75 0)
			(effects
				(font
					(size 1.27 1.27)
					(thickness 0.15)
				)
				(justify left bottom)
				(hide yes)
			)
		)
		(property "Author" "Antmicro"
			(at 387.35 31.75 0)
			(effects
				(font
					(size 1.27 1.27)
					(thickness 0.15)
				)
				(justify left bottom)
				(hide yes)
			)
		)
		(property "License" "Apache-2.0"
			(at 389.89 31.75 0)
			(effects
				(font
					(size 1.27 1.27)
					(thickness 0.15)
				)
				(justify left bottom)
				(hide yes)
			)
		)
		(pin "2"
		)
		(pin "1"
		)
		(instances
			(project "data-center-rdimm-ddr5-tester"
				(path ""
					(reference "L5")
					(unit 1)
				)
			)
		)
	)
	(symbol
		(lib_id "antmicropower:GND")
		(at 378.46 209.55 0)
		(unit 1)
		(exclude_from_sim no)
		(in_bom yes)
		(on_board yes)
		(dnp no)
		(fields_autoplaced yes)
		(property "Reference" "#PWR0503"
			(at 378.46 215.9 0)
			(effects
				(font
					(size 1.27 1.27)
				)
				(hide yes)
			)
		)
		(property "Value" "GND"
			(at 376.555 213.995 0)
			(effects
				(font
					(size 1.27 1.27)
					(thickness 0.15)
				)
				(justify left bottom)
			)
		)
		(property "Footprint" ""
			(at 387.35 217.17 0)
			(effects
				(font
					(size 1.27 1.27)
					(thickness 0.15)
				)
				(justify left bottom)
				(hide yes)
			)
		)
		(property "Datasheet" ""
			(at 387.35 222.25 0)
			(effects
				(font
					(size 1.27 1.27)
					(thickness 0.15)
				)
				(justify left bottom)
				(hide yes)
			)
		)
		(property "Description" ""
			(at 378.46 209.55 0)
			(effects
				(font
					(size 1.27 1.27)
				)
				(hide yes)
			)
		)
		(property "Author" "Antmicro"
			(at 387.35 214.63 0)
			(effects
				(font
					(size 1.27 1.27)
					(thickness 0.15)
				)
				(justify left bottom)
				(hide yes)
			)
		)
		(property "License" "Apache-2.0"
			(at 387.35 217.17 0)
			(effects
				(font
					(size 1.27 1.27)
					(thickness 0.15)
				)
				(justify left bottom)
				(hide yes)
			)
		)
		(pin "1"
		)
		(instances
			(project "data-center-rdimm-ddr5-tester"
				(path ""
					(reference "#PWR0503")
					(unit 1)
				)
			)
		)
	)
	(symbol
		(lib_id "antmicropower:+1V1")
		(at 129.54 251.46 0)
		(unit 1)
		(exclude_from_sim no)
		(in_bom yes)
		(on_board yes)
		(dnp no)
		(fields_autoplaced yes)
		(property "Reference" "#PWR0335"
			(at 129.54 255.27 0)
			(effects
				(font
					(size 1.27 1.27)
				)
				(hide yes)
			)
		)
		(property "Value" "VDDQ"
			(at 129.54 247.904 0)
			(effects
				(font
					(size 1.27 1.27)
				)
			)
		)
		(property "Footprint" ""
			(at 129.54 251.46 0)
			(effects
				(font
					(size 1.27 1.27)
				)
				(hide yes)
			)
		)
		(property "Datasheet" ""
			(at 129.54 251.46 0)
			(effects
				(font
					(size 1.27 1.27)
				)
				(hide yes)
			)
		)
		(property "Description" ""
			(at 129.54 251.46 0)
			(effects
				(font
					(size 1.27 1.27)
				)
				(hide yes)
			)
		)
		(pin "1"
		)
		(instances
			(project "data-center-rdimm-ddr5-tester"
				(path ""
					(reference "#PWR0335")
					(unit 1)
				)
			)
		)
	)
	(symbol
		(lib_id "antmicropower:GND")
		(at 387.35 166.37 0)
		(mirror y)
		(unit 1)
		(exclude_from_sim no)
		(in_bom yes)
		(on_board yes)
		(dnp no)
		(property "Reference" "#PWR0499"
			(at 387.35 172.72 0)
			(effects
				(font
					(size 1.27 1.27)
				)
				(hide yes)
			)
		)
		(property "Value" "GND"
			(at 393.7 168.91 0)
			(effects
				(font
					(size 1.27 1.27)
					(thickness 0.15)
				)
				(justify left bottom)
			)
		)
		(property "Footprint" ""
			(at 378.46 173.99 0)
			(effects
				(font
					(size 1.27 1.27)
					(thickness 0.15)
				)
				(justify left bottom)
				(hide yes)
			)
		)
		(property "Datasheet" ""
			(at 378.46 179.07 0)
			(effects
				(font
					(size 1.27 1.27)
					(thickness 0.15)
				)
				(justify left bottom)
				(hide yes)
			)
		)
		(property "Description" ""
			(at 387.35 166.37 0)
			(effects
				(font
					(size 1.27 1.27)
				)
				(hide yes)
			)
		)
		(property "Author" "Antmicro"
			(at 378.46 171.45 0)
			(effects
				(font
					(size 1.27 1.27)
					(thickness 0.15)
				)
				(justify left bottom)
				(hide yes)
			)
		)
		(property "License" "Apache-2.0"
			(at 378.46 173.99 0)
			(effects
				(font
					(size 1.27 1.27)
					(thickness 0.15)
				)
				(justify left bottom)
				(hide yes)
			)
		)
		(pin "1"
		)
		(instances
			(project "data-center-rdimm-ddr5-tester"
				(path ""
					(reference "#PWR0499")
					(unit 1)
				)
			)
		)
	)
	(symbol
		(lib_id "antmicroCapacitors0402:C_100n_0402")
		(at 114.3 264.16 270)
		(unit 1)
		(exclude_from_sim no)
		(in_bom yes)
		(on_board yes)
		(dnp no)
		(property "Reference" "C274"
			(at 113.03 270.51 0)
			(effects
				(font
					(size 1.27 1.27)
					(thickness 0.15)
				)
			)
		)
		(property "Value" "C_100n_0402"
			(at 104.14 284.48 0)
			(effects
				(font
					(size 1.27 1.27)
					(thickness 0.15)
				)
				(justify left bottom)
				(hide yes)
			)
		)
		(property "Footprint" "antmicro-footprints:C_0402_1005Metric"
			(at 101.6 284.48 0)
			(effects
				(font
					(size 1.27 1.27)
					(thickness 0.15)
				)
				(justify left bottom)
				(hide yes)
			)
		)
		(property "Datasheet" "https://www.murata.com/products/productdetail?partno=GRM155R61H104KE14%23"
			(at 99.06 284.48 0)
			(effects
				(font
					(size 1.27 1.27)
					(thickness 0.15)
				)
				(justify left bottom)
				(hide yes)
			)
		)
		(property "Description" ""
			(at 114.3 264.16 0)
			(effects
				(font
					(size 1.27 1.27)
				)
				(hide yes)
			)
		)
		(property "MPN" "GRM155R61H104KE14D"
			(at 96.52 284.48 0)
			(effects
				(font
					(size 1.27 1.27)
					(thickness 0.15)
				)
				(justify left bottom)
				(hide yes)
			)
		)
		(property "Manufacturer" "Murata"
			(at 93.98 284.48 0)
			(effects
				(font
					(size 1.27 1.27)
					(thickness 0.15)
				)
				(justify left bottom)
				(hide yes)
			)
		)
		(property "License" "Apache-2.0"
			(at 91.44 284.48 0)
			(effects
				(font
					(size 1.27 1.27)
					(thickness 0.15)
				)
				(justify left bottom)
				(hide yes)
			)
		)
		(property "Author" "Antmicro"
			(at 88.9 284.48 0)
			(effects
				(font
					(size 1.27 1.27)
					(thickness 0.15)
				)
				(justify left bottom)
				(hide yes)
			)
		)
		(property "Val" "100n"
			(at 111.76 260.35 0)
			(effects
				(font
					(size 1.27 1.27)
					(thickness 0.15)
				)
				(justify left bottom)
			)
		)
		(property "Voltage" "50V"
			(at 86.36 284.48 0)
			(effects
				(font
					(size 1.27 1.27)
				)
				(justify left bottom)
				(hide yes)
			)
		)
		(property "Dielectric" "X5R"
			(at 83.82 284.48 0)
			(effects
				(font
					(size 1.27 1.27)
				)
				(justify left bottom)
				(hide yes)
			)
		)
		(property "Public" ""
			(at 81.28 284.48 0)
			(effects
				(font
					(size 1.27 1.27)
				)
				(justify left bottom)
				(hide yes)
			)
		)
		(pin "2"
		)
		(pin "1"
		)
		(instances
			(project "data-center-rdimm-ddr5-tester"
				(path ""
					(reference "C274")
					(unit 1)
				)
			)
		)
	)
	(symbol
		(lib_id "antmicroCapacitors0402:C_100n_0402")
		(at 34.29 114.3 90)
		(unit 1)
		(exclude_from_sim no)
		(in_bom yes)
		(on_board yes)
		(dnp no)
		(fields_autoplaced yes)
		(property "Reference" "C296"
			(at 38.1 110.4836 90)
			(effects
				(font
					(size 1.27 1.27)
					(thickness 0.15)
				)
				(justify right)
			)
		)
		(property "Value" "C_100n_0402"
			(at 44.45 93.98 0)
			(effects
				(font
					(size 1.27 1.27)
					(thickness 0.15)
				)
				(justify left bottom)
				(hide yes)
			)
		)
		(property "Footprint" "antmicro-footprints:C_0402_1005Metric"
			(at 46.99 93.98 0)
			(effects
				(font
					(size 1.27 1.27)
					(thickness 0.15)
				)
				(justify left bottom)
				(hide yes)
			)
		)
		(property "Datasheet" "https://www.murata.com/products/productdetail?partno=GRM155R61H104KE14%23"
			(at 49.53 93.98 0)
			(effects
				(font
					(size 1.27 1.27)
					(thickness 0.15)
				)
				(justify left bottom)
				(hide yes)
			)
		)
		(property "Description" ""
			(at 34.29 114.3 0)
			(effects
				(font
					(size 1.27 1.27)
				)
				(hide yes)
			)
		)
		(property "MPN" "GRM155R61H104KE14D"
			(at 52.07 93.98 0)
			(effects
				(font
					(size 1.27 1.27)
					(thickness 0.15)
				)
				(justify left bottom)
				(hide yes)
			)
		)
		(property "Manufacturer" "Murata"
			(at 54.61 93.98 0)
			(effects
				(font
					(size 1.27 1.27)
					(thickness 0.15)
				)
				(justify left bottom)
				(hide yes)
			)
		)
		(property "License" "Apache-2.0"
			(at 57.15 93.98 0)
			(effects
				(font
					(size 1.27 1.27)
					(thickness 0.15)
				)
				(justify left bottom)
				(hide yes)
			)
		)
		(property "Author" "Antmicro"
			(at 59.69 93.98 0)
			(effects
				(font
					(size 1.27 1.27)
					(thickness 0.15)
				)
				(justify left bottom)
				(hide yes)
			)
		)
		(property "Val" "100n"
			(at 38.1 113.0236 90)
			(effects
				(font
					(size 1.27 1.27)
					(thickness 0.15)
				)
				(justify right)
			)
		)
		(property "Voltage" "50V"
			(at 62.23 93.98 0)
			(effects
				(font
					(size 1.27 1.27)
				)
				(justify left bottom)
				(hide yes)
			)
		)
		(property "Dielectric" "X5R"
			(at 64.77 93.98 0)
			(effects
				(font
					(size 1.27 1.27)
				)
				(justify left bottom)
				(hide yes)
			)
		)
		(pin "1"
		)
		(pin "2"
		)
		(instances
			(project "data-center-rdimm-ddr5-tester"
				(path ""
					(reference "C296")
					(unit 1)
				)
			)
		)
	)
	(symbol
		(lib_id "antmicroCapacitors0402:C_100n_0402")
		(at 109.22 264.16 270)
		(unit 1)
		(exclude_from_sim no)
		(in_bom yes)
		(on_board yes)
		(dnp no)
		(property "Reference" "C273"
			(at 107.95 270.51 0)
			(effects
				(font
					(size 1.27 1.27)
					(thickness 0.15)
				)
			)
		)
		(property "Value" "C_100n_0402"
			(at 99.06 284.48 0)
			(effects
				(font
					(size 1.27 1.27)
					(thickness 0.15)
				)
				(justify left bottom)
				(hide yes)
			)
		)
		(property "Footprint" "antmicro-footprints:C_0402_1005Metric"
			(at 96.52 284.48 0)
			(effects
				(font
					(size 1.27 1.27)
					(thickness 0.15)
				)
				(justify left bottom)
				(hide yes)
			)
		)
		(property "Datasheet" "https://www.murata.com/products/productdetail?partno=GRM155R61H104KE14%23"
			(at 93.98 284.48 0)
			(effects
				(font
					(size 1.27 1.27)
					(thickness 0.15)
				)
				(justify left bottom)
				(hide yes)
			)
		)
		(property "Description" ""
			(at 109.22 264.16 0)
			(effects
				(font
					(size 1.27 1.27)
				)
				(hide yes)
			)
		)
		(property "MPN" "GRM155R61H104KE14D"
			(at 91.44 284.48 0)
			(effects
				(font
					(size 1.27 1.27)
					(thickness 0.15)
				)
				(justify left bottom)
				(hide yes)
			)
		)
		(property "Manufacturer" "Murata"
			(at 88.9 284.48 0)
			(effects
				(font
					(size 1.27 1.27)
					(thickness 0.15)
				)
				(justify left bottom)
				(hide yes)
			)
		)
		(property "License" "Apache-2.0"
			(at 86.36 284.48 0)
			(effects
				(font
					(size 1.27 1.27)
					(thickness 0.15)
				)
				(justify left bottom)
				(hide yes)
			)
		)
		(property "Author" "Antmicro"
			(at 83.82 284.48 0)
			(effects
				(font
					(size 1.27 1.27)
					(thickness 0.15)
				)
				(justify left bottom)
				(hide yes)
			)
		)
		(property "Val" "100n"
			(at 106.68 260.35 0)
			(effects
				(font
					(size 1.27 1.27)
					(thickness 0.15)
				)
				(justify left bottom)
			)
		)
		(property "Voltage" "50V"
			(at 81.28 284.48 0)
			(effects
				(font
					(size 1.27 1.27)
				)
				(justify left bottom)
				(hide yes)
			)
		)
		(property "Dielectric" "X5R"
			(at 78.74 284.48 0)
			(effects
				(font
					(size 1.27 1.27)
				)
				(justify left bottom)
				(hide yes)
			)
		)
		(property "Public" ""
			(at 76.2 284.48 0)
			(effects
				(font
					(size 1.27 1.27)
				)
				(justify left bottom)
				(hide yes)
			)
		)
		(pin "2"
		)
		(pin "1"
		)
		(instances
			(project "data-center-rdimm-ddr5-tester"
				(path ""
					(reference "C273")
					(unit 1)
				)
			)
		)
	)
	(symbol
		(lib_id "antmicropower:PWR_FLAG")
		(at 176.53 259.08 0)
		(unit 1)
		(exclude_from_sim no)
		(in_bom yes)
		(on_board yes)
		(dnp no)
		(fields_autoplaced yes)
		(property "Reference" "#FLG023"
			(at 176.53 257.175 0)
			(effects
				(font
					(size 1.27 1.27)
				)
				(hide yes)
			)
		)
		(property "Value" "PWR_FLAG"
			(at 176.53 254 0)
			(effects
				(font
					(size 1.27 1.27)
				)
			)
		)
		(property "Footprint" ""
			(at 176.53 259.08 0)
			(effects
				(font
					(size 1.27 1.27)
				)
				(hide yes)
			)
		)
		(property "Datasheet" ""
			(at 176.53 259.08 0)
			(effects
				(font
					(size 1.27 1.27)
				)
				(hide yes)
			)
		)
		(property "Description" ""
			(at 176.53 259.08 0)
			(effects
				(font
					(size 1.27 1.27)
				)
				(hide yes)
			)
		)
		(pin "1"
		)
		(instances
			(project "data-center-rdimm-ddr5-tester"
				(path ""
					(reference "#FLG023")
					(unit 1)
				)
			)
		)
	)
	(symbol
		(lib_id "antmicropower:GND")
		(at 365.76 133.35 0)
		(unit 1)
		(exclude_from_sim no)
		(in_bom yes)
		(on_board yes)
		(dnp no)
		(fields_autoplaced yes)
		(property "Reference" "#PWR0497"
			(at 365.76 139.7 0)
			(effects
				(font
					(size 1.27 1.27)
				)
				(hide yes)
			)
		)
		(property "Value" "GND"
			(at 363.855 137.795 0)
			(effects
				(font
					(size 1.27 1.27)
					(thickness 0.15)
				)
				(justify left bottom)
			)
		)
		(property "Footprint" ""
			(at 374.65 140.97 0)
			(effects
				(font
					(size 1.27 1.27)
					(thickness 0.15)
				)
				(justify left bottom)
				(hide yes)
			)
		)
		(property "Datasheet" ""
			(at 374.65 146.05 0)
			(effects
				(font
					(size 1.27 1.27)
					(thickness 0.15)
				)
				(justify left bottom)
				(hide yes)
			)
		)
		(property "Description" ""
			(at 365.76 133.35 0)
			(effects
				(font
					(size 1.27 1.27)
				)
				(hide yes)
			)
		)
		(property "Author" "Antmicro"
			(at 374.65 138.43 0)
			(effects
				(font
					(size 1.27 1.27)
					(thickness 0.15)
				)
				(justify left bottom)
				(hide yes)
			)
		)
		(property "License" "Apache-2.0"
			(at 374.65 140.97 0)
			(effects
				(font
					(size 1.27 1.27)
					(thickness 0.15)
				)
				(justify left bottom)
				(hide yes)
			)
		)
		(pin "1"
		)
		(instances
			(project "data-center-rdimm-ddr5-tester"
				(path ""
					(reference "#PWR0497")
					(unit 1)
				)
			)
		)
	)
	(symbol
		(lib_id "antmicropower:GND")
		(at 114.3 44.45 0)
		(unit 1)
		(exclude_from_sim no)
		(in_bom yes)
		(on_board yes)
		(dnp no)
		(fields_autoplaced yes)
		(property "Reference" "#PWR0482"
			(at 123.19 46.99 0)
			(effects
				(font
					(size 1.27 1.27)
					(thickness 0.15)
				)
				(justify left bottom)
				(hide yes)
			)
		)
		(property "Value" "GND"
			(at 114.3 48.895 0)
			(effects
				(font
					(size 1.27 1.27)
					(thickness 0.15)
				)
			)
		)
		(property "Footprint" ""
			(at 123.19 52.07 0)
			(effects
				(font
					(size 1.27 1.27)
					(thickness 0.15)
				)
				(justify left bottom)
				(hide yes)
			)
		)
		(property "Datasheet" ""
			(at 123.19 57.15 0)
			(effects
				(font
					(size 1.27 1.27)
					(thickness 0.15)
				)
				(justify left bottom)
				(hide yes)
			)
		)
		(property "Description" ""
			(at 114.3 44.45 0)
			(effects
				(font
					(size 1.27 1.27)
				)
				(hide yes)
			)
		)
		(property "Author" "Antmicro"
			(at 123.19 52.07 0)
			(effects
				(font
					(size 1.27 1.27)
					(thickness 0.15)
				)
				(justify left bottom)
				(hide yes)
			)
		)
		(property "License" "Apache-2.0"
			(at 123.19 54.61 0)
			(effects
				(font
					(size 1.27 1.27)
					(thickness 0.15)
				)
				(justify left bottom)
				(hide yes)
			)
		)
		(pin "1"
		)
		(instances
			(project "data-center-rdimm-ddr5-tester"
				(path ""
					(reference "#PWR0482")
					(unit 1)
				)
			)
		)
	)
	(symbol
		(lib_id "antmicroResistors0402:R_64k9_0402")
		(at 71.12 274.32 180)
		(unit 1)
		(exclude_from_sim no)
		(in_bom no)
		(on_board yes)
		(dnp yes)
		(property "Reference" "R220"
			(at 71.12 273.05 0)
			(effects
				(font
					(size 1.27 1.27)
					(thickness 0.15)
				)
				(justify right)
			)
		)
		(property "Value" "R_64k9_0402"
			(at 50.8 261.62 0)
			(effects
				(font
					(size 1.27 1.27)
					(thickness 0.15)
				)
				(justify left bottom)
				(hide yes)
			)
		)
		(property "Footprint" "antmicro-footprints:R_0402_1005Metric"
			(at 50.8 259.08 0)
			(effects
				(font
					(size 1.27 1.27)
					(thickness 0.15)
				)
				(justify left bottom)
				(hide yes)
			)
		)
		(property "Datasheet" "https://www.bourns.com/docs/product-datasheets/cr.pdf"
			(at 50.8 256.54 0)
			(effects
				(font
					(size 1.27 1.27)
					(thickness 0.15)
				)
				(justify left bottom)
				(hide yes)
			)
		)
		(property "Description" ""
			(at 71.12 274.32 0)
			(effects
				(font
					(size 1.27 1.27)
				)
				(hide yes)
			)
		)
		(property "MPN" "CR0402-FX-6492GLF"
			(at 50.8 254 0)
			(effects
				(font
					(size 1.27 1.27)
					(thickness 0.15)
				)
				(justify left bottom)
				(hide yes)
			)
		)
		(property "Manufacturer" "Bourns"
			(at 50.8 251.46 0)
			(effects
				(font
					(size 1.27 1.27)
					(thickness 0.15)
				)
				(justify left bottom)
				(hide yes)
			)
		)
		(property "License" "Apache-2.0"
			(at 50.8 248.92 0)
			(effects
				(font
					(size 1.27 1.27)
					(thickness 0.15)
				)
				(justify left bottom)
				(hide yes)
			)
		)
		(property "Author" "Antmicro"
			(at 50.8 246.38 0)
			(effects
				(font
					(size 1.27 1.27)
					(thickness 0.15)
				)
				(justify left bottom)
				(hide yes)
			)
		)
		(property "Val" "64k9"
			(at 60.96 273.05 0)
			(effects
				(font
					(size 1.27 1.27)
					(thickness 0.15)
				)
				(justify right)
			)
		)
		(property "Tolerance" "1%"
			(at 50.8 264.16 0)
			(effects
				(font
					(size 1.27 1.27)
				)
				(justify left bottom)
				(hide yes)
			)
		)
		(pin "2"
		)
		(pin "1"
		)
		(instances
			(project "data-center-rdimm-ddr5-tester"
				(path ""
					(reference "R220")
					(unit 1)
				)
			)
		)
	)
	(symbol
		(lib_id "antmicropower:+3V3")
		(at 354.33 102.87 0)
		(unit 1)
		(exclude_from_sim no)
		(in_bom yes)
		(on_board yes)
		(dnp no)
		(property "Reference" "#PWR0498"
			(at 369.57 102.87 0)
			(effects
				(font
					(size 1.27 1.27)
					(thickness 0.15)
				)
				(justify left bottom)
				(hide yes)
			)
		)
		(property "Value" "+3V3"
			(at 354.33 99.06 0)
			(effects
				(font
					(size 1.27 1.27)
					(thickness 0.15)
				)
			)
		)
		(property "Footprint" ""
			(at 369.57 110.49 0)
			(effects
				(font
					(size 1.27 1.27)
					(thickness 0.15)
				)
				(justify left bottom)
				(hide yes)
			)
		)
		(property "Datasheet" ""
			(at 369.57 113.03 0)
			(effects
				(font
					(size 1.27 1.27)
					(thickness 0.15)
				)
				(justify left bottom)
				(hide yes)
			)
		)
		(property "Description" ""
			(at 354.33 102.87 0)
			(effects
				(font
					(size 1.27 1.27)
				)
				(hide yes)
			)
		)
		(property "Author" "Antmicro"
			(at 369.57 105.41 0)
			(effects
				(font
					(size 1.27 1.27)
					(thickness 0.15)
				)
				(justify left bottom)
				(hide yes)
			)
		)
		(property "License" "Apache-2.0"
			(at 369.57 107.95 0)
			(effects
				(font
					(size 1.27 1.27)
					(thickness 0.15)
				)
				(justify left bottom)
				(hide yes)
			)
		)
		(pin "1"
		)
		(instances
			(project "data-center-rdimm-ddr5-tester"
				(path ""
					(reference "#PWR0498")
					(unit 1)
				)
			)
		)
	)
	(symbol
		(lib_id "antmicroTVSDiodes:TPD4E05U06QDQARQ1")
		(at 308.61 233.68 0)
		(unit 1)
		(exclude_from_sim no)
		(in_bom yes)
		(on_board yes)
		(dnp no)
		(fields_autoplaced yes)
		(property "Reference" "U10"
			(at 314.325 226.06 0)
			(effects
				(font
					(size 1.27 1.27)
				)
			)
		)
		(property "Value" "TPD4E05U06QDQARQ1"
			(at 311.15 247.015 0)
			(effects
				(font
					(size 1.27 1.27)
					(thickness 0.15)
				)
				(justify left)
				(hide yes)
			)
		)
		(property "Footprint" "antmicro-footprints:USON-10_2.5x1mm_P0.5mm"
			(at 332.74 238.76 0)
			(effects
				(font
					(size 1.27 1.27)
					(thickness 0.15)
				)
				(justify left bottom)
				(hide yes)
			)
		)
		(property "Datasheet" "https://www.ti.com/lit/ds/symlink/tpd4e05u06-q1.pdf?HQS=dis-mous-null-mousermode-dsf-pf-null-wwe&ts=1663591265741&ref_url=https%253A%252F%252Fwww.mouser.com%252F"
			(at 332.74 241.3 0)
			(effects
				(font
					(size 1.27 1.27)
					(thickness 0.15)
				)
				(justify left bottom)
				(hide yes)
			)
		)
		(property "Description" ""
			(at 308.61 233.68 0)
			(effects
				(font
					(size 1.27 1.27)
				)
				(hide yes)
			)
		)
		(property "Manufacturer" "Texas Instruments"
			(at 332.74 243.84 0)
			(effects
				(font
					(size 1.27 1.27)
					(thickness 0.15)
				)
				(justify left bottom)
				(hide yes)
			)
		)
		(property "MPN" "TPD4E05U06QDQARQ1"
			(at 314.325 228.6 0)
			(effects
				(font
					(size 1.27 1.27)
					(thickness 0.15)
				)
			)
		)
		(property "Author" "Antmicro"
			(at 332.74 248.92 0)
			(effects
				(font
					(size 1.27 1.27)
					(thickness 0.15)
				)
				(justify left bottom)
				(hide yes)
			)
		)
		(property "License" "Apache-2.0"
			(at 332.74 251.46 0)
			(effects
				(font
					(size 1.27 1.27)
					(thickness 0.15)
				)
				(justify left bottom)
				(hide yes)
			)
		)
		(pin "1"
		)
		(pin "10"
		)
		(pin "2"
		)
		(pin "3"
		)
		(pin "4"
		)
		(pin "5"
		)
		(pin "6"
		)
		(pin "7"
		)
		(pin "8"
		)
		(pin "9"
		)
		(instances
			(project "data-center-rdimm-ddr5-tester"
				(path ""
					(reference "U10")
					(unit 1)
				)
			)
		)
	)
	(symbol
		(lib_id "antmicroCapacitors0402:C_100n_0402")
		(at 163.83 264.16 270)
		(unit 1)
		(exclude_from_sim no)
		(in_bom yes)
		(on_board yes)
		(dnp no)
		(property "Reference" "C282"
			(at 162.56 270.51 0)
			(effects
				(font
					(size 1.27 1.27)
					(thickness 0.15)
				)
			)
		)
		(property "Value" "C_100n_0402"
			(at 153.67 284.48 0)
			(effects
				(font
					(size 1.27 1.27)
					(thickness 0.15)
				)
				(justify left bottom)
				(hide yes)
			)
		)
		(property "Footprint" "antmicro-footprints:C_0402_1005Metric"
			(at 151.13 284.48 0)
			(effects
				(font
					(size 1.27 1.27)
					(thickness 0.15)
				)
				(justify left bottom)
				(hide yes)
			)
		)
		(property "Datasheet" "https://www.murata.com/products/productdetail?partno=GRM155R61H104KE14%23"
			(at 148.59 284.48 0)
			(effects
				(font
					(size 1.27 1.27)
					(thickness 0.15)
				)
				(justify left bottom)
				(hide yes)
			)
		)
		(property "Description" ""
			(at 163.83 264.16 0)
			(effects
				(font
					(size 1.27 1.27)
				)
				(hide yes)
			)
		)
		(property "MPN" "GRM155R61H104KE14D"
			(at 146.05 284.48 0)
			(effects
				(font
					(size 1.27 1.27)
					(thickness 0.15)
				)
				(justify left bottom)
				(hide yes)
			)
		)
		(property "Manufacturer" "Murata"
			(at 143.51 284.48 0)
			(effects
				(font
					(size 1.27 1.27)
					(thickness 0.15)
				)
				(justify left bottom)
				(hide yes)
			)
		)
		(property "License" "Apache-2.0"
			(at 140.97 284.48 0)
			(effects
				(font
					(size 1.27 1.27)
					(thickness 0.15)
				)
				(justify left bottom)
				(hide yes)
			)
		)
		(property "Author" "Antmicro"
			(at 138.43 284.48 0)
			(effects
				(font
					(size 1.27 1.27)
					(thickness 0.15)
				)
				(justify left bottom)
				(hide yes)
			)
		)
		(property "Val" "100n"
			(at 161.29 260.35 0)
			(effects
				(font
					(size 1.27 1.27)
					(thickness 0.15)
				)
				(justify left bottom)
			)
		)
		(property "Voltage" "50V"
			(at 135.89 284.48 0)
			(effects
				(font
					(size 1.27 1.27)
				)
				(justify left bottom)
				(hide yes)
			)
		)
		(property "Dielectric" "X5R"
			(at 133.35 284.48 0)
			(effects
				(font
					(size 1.27 1.27)
				)
				(justify left bottom)
				(hide yes)
			)
		)
		(property "Public" ""
			(at 130.81 284.48 0)
			(effects
				(font
					(size 1.27 1.27)
				)
				(justify left bottom)
				(hide yes)
			)
		)
		(pin "2"
		)
		(pin "1"
		)
		(instances
			(project "data-center-rdimm-ddr5-tester"
				(path ""
					(reference "C282")
					(unit 1)
				)
			)
		)
	)
	(symbol
		(lib_id "antmicroResistors0402:R_2k2_0402")
		(at 46.99 180.34 90)
		(unit 1)
		(exclude_from_sim no)
		(in_bom yes)
		(on_board yes)
		(dnp no)
		(property "Reference" "R234"
			(at 48.387 175.641 0)
			(effects
				(font
					(size 1.27 1.27)
					(thickness 0.15)
				)
				(justify left)
			)
		)
		(property "Value" "R_2k2_0402"
			(at 59.69 160.02 0)
			(effects
				(font
					(size 1.27 1.27)
					(thickness 0.15)
				)
				(justify left bottom)
				(hide yes)
			)
		)
		(property "Footprint" "antmicro-footprints:R_0402_1005Metric"
			(at 62.23 160.02 0)
			(effects
				(font
					(size 1.27 1.27)
					(thickness 0.15)
				)
				(justify left bottom)
				(hide yes)
			)
		)
		(property "Datasheet" "https://www.bourns.com/docs/product-datasheets/cr.pdf"
			(at 64.77 160.02 0)
			(effects
				(font
					(size 1.27 1.27)
					(thickness 0.15)
				)
				(justify left bottom)
				(hide yes)
			)
		)
		(property "Description" ""
			(at 46.99 180.34 0)
			(effects
				(font
					(size 1.27 1.27)
				)
				(hide yes)
			)
		)
		(property "MPN" "CR0402-FX-2201GLF"
			(at 67.31 160.02 0)
			(effects
				(font
					(size 1.27 1.27)
					(thickness 0.15)
				)
				(justify left bottom)
				(hide yes)
			)
		)
		(property "Manufacturer" "Bourns"
			(at 69.85 160.02 0)
			(effects
				(font
					(size 1.27 1.27)
					(thickness 0.15)
				)
				(justify left bottom)
				(hide yes)
			)
		)
		(property "License" "Apache-2.0"
			(at 72.39 160.02 0)
			(effects
				(font
					(size 1.27 1.27)
					(thickness 0.15)
				)
				(justify left bottom)
				(hide yes)
			)
		)
		(property "Author" "Antmicro"
			(at 74.93 160.02 0)
			(effects
				(font
					(size 1.27 1.27)
					(thickness 0.15)
				)
				(justify left bottom)
				(hide yes)
			)
		)
		(property "Val" "2k2"
			(at 48.514 183.642 0)
			(effects
				(font
					(size 1.27 1.27)
					(thickness 0.15)
				)
				(justify left)
			)
		)
		(property "Tolerance" "1%"
			(at 57.15 160.02 0)
			(effects
				(font
					(size 1.27 1.27)
				)
				(justify left bottom)
				(hide yes)
			)
		)
		(property "Public" ""
			(at 77.47 160.02 0)
			(effects
				(font
					(size 1.27 1.27)
				)
				(justify left bottom)
				(hide yes)
			)
		)
		(pin "1"
		)
		(pin "2"
		)
		(instances
			(project "data-center-rdimm-ddr5-tester"
				(path ""
					(reference "R234")
					(unit 1)
				)
			)
		)
	)
	(symbol
		(lib_id "antmicroResistors0402:R_0R_0402")
		(at 113.03 184.15 0)
		(unit 1)
		(exclude_from_sim no)
		(in_bom yes)
		(on_board yes)
		(dnp no)
		(property "Reference" "R38"
			(at 111.76 182.88 0)
			(effects
				(font
					(size 1.27 1.27)
					(thickness 0.15)
				)
			)
		)
		(property "Value" "R_0R_0402"
			(at 133.35 196.85 0)
			(effects
				(font
					(size 1.27 1.27)
					(thickness 0.15)
				)
				(justify left bottom)
				(hide yes)
			)
		)
		(property "Footprint" "antmicro-footprints:R_0402_1005Metric"
			(at 133.35 199.39 0)
			(effects
				(font
					(size 1.27 1.27)
					(thickness 0.15)
				)
				(justify left bottom)
				(hide yes)
			)
		)
		(property "Datasheet" "https://industrial.panasonic.com/cdbs/www-data/pdf/RDA0000/AOA0000C301.pdf"
			(at 133.35 201.93 0)
			(effects
				(font
					(size 1.27 1.27)
					(thickness 0.15)
				)
				(justify left bottom)
				(hide yes)
			)
		)
		(property "Description" ""
			(at 113.03 184.15 0)
			(effects
				(font
					(size 1.27 1.27)
				)
				(hide yes)
			)
		)
		(property "MPN" "ERJ2GE0R00X"
			(at 133.35 204.47 0)
			(effects
				(font
					(size 1.27 1.27)
					(thickness 0.15)
				)
				(justify left bottom)
				(hide yes)
			)
		)
		(property "Manufacturer" "Panasonic"
			(at 133.35 207.01 0)
			(effects
				(font
					(size 1.27 1.27)
					(thickness 0.15)
				)
				(justify left bottom)
				(hide yes)
			)
		)
		(property "License" "Apache-2.0"
			(at 133.35 209.55 0)
			(effects
				(font
					(size 1.27 1.27)
					(thickness 0.15)
				)
				(justify left bottom)
				(hide yes)
			)
		)
		(property "Author" "Antmicro"
			(at 133.35 212.09 0)
			(effects
				(font
					(size 1.27 1.27)
					(thickness 0.15)
				)
				(justify left bottom)
				(hide yes)
			)
		)
		(property "Val" "0R"
			(at 119.38 182.88 0)
			(effects
				(font
					(size 1.27 1.27)
					(thickness 0.15)
				)
			)
		)
		(property "Tolerance" "~"
			(at 133.35 194.31 0)
			(effects
				(font
					(size 1.27 1.27)
				)
				(justify left bottom)
				(hide yes)
			)
		)
		(property "Current" "1A"
			(at 133.35 214.63 0)
			(effects
				(font
					(size 1.27 1.27)
					(thickness 0.15)
				)
				(justify left bottom)
				(hide yes)
			)
		)
		(pin "1"
		)
		(pin "2"
		)
		(instances
			(project "data-center-rdimm-ddr5-tester"
				(path ""
					(reference "R38")
					(unit 1)
				)
			)
		)
	)
	(symbol
		(lib_id "antmicroResistors0402:R_0R_0402")
		(at 137.16 257.81 90)
		(unit 1)
		(exclude_from_sim no)
		(in_bom yes)
		(on_board yes)
		(dnp no)
		(property "Reference" "R248"
			(at 138.43 254 90)
			(effects
				(font
					(size 1.27 1.27)
					(thickness 0.15)
				)
				(justify right)
			)
		)
		(property "Value" "R_0R_0402"
			(at 149.86 237.49 0)
			(effects
				(font
					(size 1.27 1.27)
					(thickness 0.15)
				)
				(justify left bottom)
				(hide yes)
			)
		)
		(property "Footprint" "antmicro-footprints:R_0402_1005Metric"
			(at 152.4 237.49 0)
			(effects
				(font
					(size 1.27 1.27)
					(thickness 0.15)
				)
				(justify left bottom)
				(hide yes)
			)
		)
		(property "Datasheet" "https://industrial.panasonic.com/cdbs/www-data/pdf/RDA0000/AOA0000C301.pdf"
			(at 154.94 237.49 0)
			(effects
				(font
					(size 1.27 1.27)
					(thickness 0.15)
				)
				(justify left bottom)
				(hide yes)
			)
		)
		(property "Description" ""
			(at 137.16 257.81 0)
			(effects
				(font
					(size 1.27 1.27)
				)
				(hide yes)
			)
		)
		(property "MPN" "ERJ2GE0R00X"
			(at 157.48 237.49 0)
			(effects
				(font
					(size 1.27 1.27)
					(thickness 0.15)
				)
				(justify left bottom)
				(hide yes)
			)
		)
		(property "Manufacturer" "Panasonic"
			(at 160.02 237.49 0)
			(effects
				(font
					(size 1.27 1.27)
					(thickness 0.15)
				)
				(justify left bottom)
				(hide yes)
			)
		)
		(property "License" "Apache-2.0"
			(at 162.56 237.49 0)
			(effects
				(font
					(size 1.27 1.27)
					(thickness 0.15)
				)
				(justify left bottom)
				(hide yes)
			)
		)
		(property "Author" "Antmicro"
			(at 165.1 237.49 0)
			(effects
				(font
					(size 1.27 1.27)
					(thickness 0.15)
				)
				(justify left bottom)
				(hide yes)
			)
		)
		(property "Val" "0R"
			(at 138.43 256.54 90)
			(effects
				(font
					(size 1.27 1.27)
					(thickness 0.15)
				)
				(justify right)
			)
		)
		(property "Tolerance" "~"
			(at 147.32 237.49 0)
			(effects
				(font
					(size 1.27 1.27)
				)
				(justify left bottom)
				(hide yes)
			)
		)
		(property "Current" "1A"
			(at 167.64 237.49 0)
			(effects
				(font
					(size 1.27 1.27)
					(thickness 0.15)
				)
				(justify left bottom)
				(hide yes)
			)
		)
		(pin "1"
		)
		(pin "2"
		)
		(instances
			(project "data-center-rdimm-ddr5-tester"
				(path ""
					(reference "R248")
					(unit 1)
				)
			)
		)
	)
	(symbol
		(lib_id "antmicroTransistorsFETsMOSFETsSingle:BSS138PW")
		(at 303.53 104.14 0)
		(unit 1)
		(exclude_from_sim no)
		(in_bom yes)
		(on_board yes)
		(dnp no)
		(property "Reference" "Q19"
			(at 313.69 100.33 0)
			(effects
				(font
					(size 1.27 1.27)
				)
				(justify left)
			)
		)
		(property "Value" "BSS138PW"
			(at 313.944 103.2997 0)
			(effects
				(font
					(size 1.27 1.27)
					(thickness 0.15)
				)
				(justify left)
				(hide yes)
			)
		)
		(property "Footprint" "antmicro-footprints:SC70-3"
			(at 326.39 115.57 0)
			(effects
				(font
					(size 1.27 1.27)
					(thickness 0.15)
				)
				(justify left bottom)
				(hide yes)
			)
		)
		(property "Datasheet" "https://assets.nexperia.com/documents/data-sheet/BSS138PW.pdf"
			(at 326.39 118.11 0)
			(effects
				(font
					(size 1.27 1.27)
					(thickness 0.15)
				)
				(justify left bottom)
				(hide yes)
			)
		)
		(property "Description" ""
			(at 303.53 104.14 0)
			(effects
				(font
					(size 1.27 1.27)
				)
				(hide yes)
			)
		)
		(property "MPN" "BSS138PW"
			(at 313.69 102.87 0)
			(effects
				(font
					(size 1.27 1.27)
					(thickness 0.15)
				)
				(justify left)
			)
		)
		(property "Manufacturer" "Nexperia"
			(at 326.39 123.19 0)
			(effects
				(font
					(size 1.27 1.27)
					(thickness 0.15)
				)
				(justify left bottom)
				(hide yes)
			)
		)
		(property "Author" "Antmicro"
			(at 326.39 125.73 0)
			(effects
				(font
					(size 1.27 1.27)
					(thickness 0.15)
				)
				(justify left bottom)
				(hide yes)
			)
		)
		(property "License" "Apache-2.0"
			(at 326.39 128.27 0)
			(effects
				(font
					(size 1.27 1.27)
					(thickness 0.15)
				)
				(justify left bottom)
				(hide yes)
			)
		)
		(pin "1"
		)
		(pin "2"
		)
		(pin "3"
		)
		(instances
			(project "data-center-rdimm-ddr5-tester"
				(path ""
					(reference "Q19")
					(unit 1)
				)
			)
		)
	)
	(symbol
		(lib_id "antmicroResistors0402:R_64k9_0402")
		(at 71.12 266.7 180)
		(unit 1)
		(exclude_from_sim no)
		(in_bom no)
		(on_board yes)
		(dnp yes)
		(property "Reference" "R217"
			(at 71.12 265.43 0)
			(effects
				(font
					(size 1.27 1.27)
					(thickness 0.15)
				)
				(justify right)
			)
		)
		(property "Value" "R_64k9_0402"
			(at 50.8 254 0)
			(effects
				(font
					(size 1.27 1.27)
					(thickness 0.15)
				)
				(justify left bottom)
				(hide yes)
			)
		)
		(property "Footprint" "antmicro-footprints:R_0402_1005Metric"
			(at 50.8 251.46 0)
			(effects
				(font
					(size 1.27 1.27)
					(thickness 0.15)
				)
				(justify left bottom)
				(hide yes)
			)
		)
		(property "Datasheet" "https://www.bourns.com/docs/product-datasheets/cr.pdf"
			(at 50.8 248.92 0)
			(effects
				(font
					(size 1.27 1.27)
					(thickness 0.15)
				)
				(justify left bottom)
				(hide yes)
			)
		)
		(property "Description" ""
			(at 71.12 266.7 0)
			(effects
				(font
					(size 1.27 1.27)
				)
				(hide yes)
			)
		)
		(property "MPN" "CR0402-FX-6492GLF"
			(at 50.8 246.38 0)
			(effects
				(font
					(size 1.27 1.27)
					(thickness 0.15)
				)
				(justify left bottom)
				(hide yes)
			)
		)
		(property "Manufacturer" "Bourns"
			(at 50.8 243.84 0)
			(effects
				(font
					(size 1.27 1.27)
					(thickness 0.15)
				)
				(justify left bottom)
				(hide yes)
			)
		)
		(property "License" "Apache-2.0"
			(at 50.8 241.3 0)
			(effects
				(font
					(size 1.27 1.27)
					(thickness 0.15)
				)
				(justify left bottom)
				(hide yes)
			)
		)
		(property "Author" "Antmicro"
			(at 50.8 238.76 0)
			(effects
				(font
					(size 1.27 1.27)
					(thickness 0.15)
				)
				(justify left bottom)
				(hide yes)
			)
		)
		(property "Val" "64k9"
			(at 60.96 265.43 0)
			(effects
				(font
					(size 1.27 1.27)
					(thickness 0.15)
				)
				(justify right)
			)
		)
		(property "Tolerance" "1%"
			(at 50.8 256.54 0)
			(effects
				(font
					(size 1.27 1.27)
				)
				(justify left bottom)
				(hide yes)
			)
		)
		(pin "2"
		)
		(pin "1"
		)
		(instances
			(project "data-center-rdimm-ddr5-tester"
				(path ""
					(reference "R217")
					(unit 1)
				)
			)
		)
	)
	(symbol
		(lib_id "antmicroTVSDiodes:PESD5V0X1UB")
		(at 163.83 90.17 90)
		(mirror x)
		(unit 1)
		(exclude_from_sim no)
		(in_bom yes)
		(on_board yes)
		(dnp no)
		(fields_autoplaced yes)
		(property "Reference" "D19"
			(at 166.37 91.44 90)
			(effects
				(font
					(size 1.27 1.27)
					(thickness 0.15)
				)
				(justify right)
			)
		)
		(property "Value" "PESD5V0X1UB"
			(at 168.91 105.41 0)
			(effects
				(font
					(size 1.27 1.27)
					(thickness 0.15)
				)
				(justify left bottom)
				(hide yes)
			)
		)
		(property "Footprint" "antmicro-footprints:SOD-523"
			(at 171.45 105.41 0)
			(effects
				(font
					(size 1.27 1.27)
					(thickness 0.15)
				)
				(justify left bottom)
				(hide yes)
			)
		)
		(property "Datasheet" "https://assets.nexperia.com/documents/data-sheet/PESD5V0X1UB.pdf"
			(at 173.99 105.41 0)
			(effects
				(font
					(size 1.27 1.27)
					(thickness 0.15)
				)
				(justify left bottom)
				(hide yes)
			)
		)
		(property "Description" ""
			(at 163.83 90.17 0)
			(effects
				(font
					(size 1.27 1.27)
				)
				(hide yes)
			)
		)
		(property "MPN" "PESD5V0X1UB,135"
			(at 166.37 93.98 90)
			(effects
				(font
					(size 1.27 1.27)
					(thickness 0.15)
				)
				(justify right)
			)
		)
		(property "Manufacturer" "Nexperia"
			(at 176.53 105.41 0)
			(effects
				(font
					(size 1.27 1.27)
					(thickness 0.15)
				)
				(justify left bottom)
				(hide yes)
			)
		)
		(property "Author" "Antmicro"
			(at 179.07 105.41 0)
			(effects
				(font
					(size 1.27 1.27)
					(thickness 0.15)
				)
				(justify left bottom)
				(hide yes)
			)
		)
		(property "License" "Apache-2.0"
			(at 181.61 105.41 0)
			(effects
				(font
					(size 1.27 1.27)
					(thickness 0.15)
				)
				(justify left bottom)
				(hide yes)
			)
		)
		(pin "1"
		)
		(pin "2"
		)
		(instances
			(project "data-center-rdimm-ddr5-tester"
				(path ""
					(reference "D19")
					(unit 1)
				)
			)
		)
	)
	(symbol
		(lib_id "antmicropower:PWR_FLAG")
		(at 201.93 214.63 0)
		(unit 1)
		(exclude_from_sim no)
		(in_bom yes)
		(on_board yes)
		(dnp no)
		(fields_autoplaced yes)
		(property "Reference" "#FLG03"
			(at 201.93 212.725 0)
			(effects
				(font
					(size 1.27 1.27)
				)
				(hide yes)
			)
		)
		(property "Value" "PWR_FLAG"
			(at 201.93 211.0542 0)
			(effects
				(font
					(size 1.27 1.27)
				)
			)
		)
		(property "Footprint" ""
			(at 201.93 214.63 0)
			(effects
				(font
					(size 1.27 1.27)
				)
				(hide yes)
			)
		)
		(property "Datasheet" ""
			(at 201.93 214.63 0)
			(effects
				(font
					(size 1.27 1.27)
				)
				(hide yes)
			)
		)
		(property "Description" ""
			(at 201.93 214.63 0)
			(effects
				(font
					(size 1.27 1.27)
				)
				(hide yes)
			)
		)
		(pin "1"
		)
		(instances
			(project "data-center-rdimm-ddr5-tester"
				(path ""
					(reference "#FLG03")
					(unit 1)
				)
			)
		)
	)
	(symbol
		(lib_id "antmicroTVSDiodes:TPD4E05U06QDQARQ1")
		(at 379.73 195.58 0)
		(unit 1)
		(exclude_from_sim no)
		(in_bom yes)
		(on_board yes)
		(dnp no)
		(property "Reference" "U47"
			(at 382.27 191.77 0)
			(effects
				(font
					(size 1.27 1.27)
				)
				(justify left)
			)
		)
		(property "Value" "TPD4E05U06QDQARQ1"
			(at 382.27 208.915 0)
			(effects
				(font
					(size 1.27 1.27)
					(thickness 0.15)
				)
				(justify left)
				(hide yes)
			)
		)
		(property "Footprint" "antmicro-footprints:USON-10_2.5x1mm_P0.5mm"
			(at 403.86 200.66 0)
			(effects
				(font
					(size 1.27 1.27)
					(thickness 0.15)
				)
				(justify left bottom)
				(hide yes)
			)
		)
		(property "Datasheet" "https://www.ti.com/lit/ds/symlink/tpd4e05u06-q1.pdf?HQS=dis-mous-null-mousermode-dsf-pf-null-wwe&ts=1663591265741&ref_url=https%253A%252F%252Fwww.mouser.com%252F"
			(at 403.86 203.2 0)
			(effects
				(font
					(size 1.27 1.27)
					(thickness 0.15)
				)
				(justify left bottom)
				(hide yes)
			)
		)
		(property "Description" ""
			(at 379.73 195.58 0)
			(effects
				(font
					(size 1.27 1.27)
				)
				(hide yes)
			)
		)
		(property "Manufacturer" "Texas Instruments"
			(at 403.86 205.74 0)
			(effects
				(font
					(size 1.27 1.27)
					(thickness 0.15)
				)
				(justify left bottom)
				(hide yes)
			)
		)
		(property "MPN" "TPD4E05U06QDQARQ1"
			(at 379.095 208.915 0)
			(effects
				(font
					(size 1.27 1.27)
					(thickness 0.15)
				)
				(justify left)
			)
		)
		(property "Author" "Antmicro"
			(at 403.86 210.82 0)
			(effects
				(font
					(size 1.27 1.27)
					(thickness 0.15)
				)
				(justify left bottom)
				(hide yes)
			)
		)
		(property "License" "Apache-2.0"
			(at 403.86 213.36 0)
			(effects
				(font
					(size 1.27 1.27)
					(thickness 0.15)
				)
				(justify left bottom)
				(hide yes)
			)
		)
		(pin "1"
		)
		(pin "10"
		)
		(pin "2"
		)
		(pin "3"
		)
		(pin "4"
		)
		(pin "5"
		)
		(pin "6"
		)
		(pin "7"
		)
		(pin "8"
		)
		(pin "9"
		)
		(instances
			(project "data-center-rdimm-ddr5-tester"
				(path ""
					(reference "U47")
					(unit 1)
				)
			)
		)
	)
	(symbol
		(lib_id "antmicroDiodesRectifiersSingle:BAT54-02V-G3-08")
		(at 191.77 215.9 180)
		(unit 1)
		(exclude_from_sim no)
		(in_bom yes)
		(on_board yes)
		(dnp no)
		(property "Reference" "D14"
			(at 189.23 213.36 0)
			(effects
				(font
					(size 1.27 1.27)
				)
			)
		)
		(property "Value" "BAT54-02V-G3-08"
			(at 188.595 212.09 0)
			(effects
				(font
					(size 1.27 1.27)
					(thickness 0.15)
				)
				(hide yes)
			)
		)
		(property "Footprint" "antmicro-footprints:SOD-523"
			(at 170.18 205.74 0)
			(effects
				(font
					(size 1.27 1.27)
					(thickness 0.15)
				)
				(justify left bottom)
				(hide yes)
			)
		)
		(property "Datasheet" "https://www.vishay.com/docs/85633/bat5402v.pdf"
			(at 170.18 203.2 0)
			(effects
				(font
					(size 1.27 1.27)
					(thickness 0.15)
				)
				(justify left bottom)
				(hide yes)
			)
		)
		(property "Description" ""
			(at 191.77 215.9 0)
			(effects
				(font
					(size 1.27 1.27)
				)
				(hide yes)
			)
		)
		(property "MPN" "BAT54-02V-G3-08"
			(at 189.23 218.44 0)
			(effects
				(font
					(size 1.27 1.27)
					(thickness 0.15)
				)
			)
		)
		(property "Manufacturer" "Vishay"
			(at 170.18 198.12 0)
			(effects
				(font
					(size 1.27 1.27)
					(thickness 0.15)
				)
				(justify left bottom)
				(hide yes)
			)
		)
		(property "Author" "Antmicro"
			(at 170.18 195.58 0)
			(effects
				(font
					(size 1.27 1.27)
					(thickness 0.15)
				)
				(justify left bottom)
				(hide yes)
			)
		)
		(property "License" "Apache-2.0"
			(at 170.18 193.04 0)
			(effects
				(font
					(size 1.27 1.27)
					(thickness 0.15)
				)
				(justify left bottom)
				(hide yes)
			)
		)
		(pin "1"
		)
		(pin "2"
		)
		(instances
			(project "data-center-rdimm-ddr5-tester"
				(path ""
					(reference "D14")
					(unit 1)
				)
			)
		)
	)
	(symbol
		(lib_id "antmicroResistors0402:R_330R_0402")
		(at 259.08 220.98 0)
		(mirror y)
		(unit 1)
		(exclude_from_sim no)
		(in_bom yes)
		(on_board yes)
		(dnp no)
		(property "Reference" "R89"
			(at 256.54 215.9 0)
			(effects
				(font
					(size 1.27 1.27)
				)
			)
		)
		(property "Value" "R_330R_0402"
			(at 238.76 233.68 0)
			(effects
				(font
					(size 1.27 1.27)
					(thickness 0.15)
				)
				(justify left bottom)
				(hide yes)
			)
		)
		(property "Footprint" "antmicro-footprints:R_0402_1005Metric"
			(at 238.76 236.22 0)
			(effects
				(font
					(size 1.27 1.27)
					(thickness 0.15)
				)
				(justify left bottom)
				(hide yes)
			)
		)
		(property "Datasheet" "https://www.bourns.com/docs/product-datasheets/cr.pdf"
			(at 238.76 238.76 0)
			(effects
				(font
					(size 1.27 1.27)
					(thickness 0.15)
				)
				(justify left bottom)
				(hide yes)
			)
		)
		(property "Description" ""
			(at 259.08 220.98 0)
			(effects
				(font
					(size 1.27 1.27)
				)
				(hide yes)
			)
		)
		(property "Manufacturer" "Bourns"
			(at 238.76 243.84 0)
			(effects
				(font
					(size 1.27 1.27)
					(thickness 0.15)
				)
				(justify left bottom)
				(hide yes)
			)
		)
		(property "MPN" "CR0402-FX-3300GLF"
			(at 238.76 241.3 0)
			(effects
				(font
					(size 1.27 1.27)
					(thickness 0.15)
				)
				(justify left bottom)
				(hide yes)
			)
		)
		(property "Val" "330R"
			(at 256.54 218.44 0)
			(effects
				(font
					(size 1.27 1.27)
					(thickness 0.15)
				)
			)
		)
		(property "License" "Apache-2.0"
			(at 238.76 246.38 0)
			(effects
				(font
					(size 1.27 1.27)
					(thickness 0.15)
				)
				(justify left bottom)
				(hide yes)
			)
		)
		(property "Author" "Antmicro"
			(at 238.76 248.92 0)
			(effects
				(font
					(size 1.27 1.27)
					(thickness 0.15)
				)
				(justify left bottom)
				(hide yes)
			)
		)
		(property "Tolerance" "1%"
			(at 238.76 231.14 0)
			(effects
				(font
					(size 1.27 1.27)
				)
				(justify left bottom)
				(hide yes)
			)
		)
		(pin "1"
		)
		(pin "2"
		)
		(instances
			(project "data-center-rdimm-ddr5-tester"
				(path ""
					(reference "R89")
					(unit 1)
				)
			)
		)
	)
	(symbol
		(lib_id "antmicropower:+3V3")
		(at 177.8 53.34 0)
		(unit 1)
		(exclude_from_sim no)
		(in_bom yes)
		(on_board yes)
		(dnp no)
		(fields_autoplaced yes)
		(property "Reference" "#PWR0218"
			(at 193.04 53.34 0)
			(effects
				(font
					(size 1.27 1.27)
					(thickness 0.15)
				)
				(justify left bottom)
				(hide yes)
			)
		)
		(property "Value" "+3V3"
			(at 177.8 48.895 0)
			(effects
				(font
					(size 1.27 1.27)
					(thickness 0.15)
				)
			)
		)
		(property "Footprint" ""
			(at 193.04 60.96 0)
			(effects
				(font
					(size 1.27 1.27)
					(thickness 0.15)
				)
				(justify left bottom)
				(hide yes)
			)
		)
		(property "Datasheet" ""
			(at 193.04 63.5 0)
			(effects
				(font
					(size 1.27 1.27)
					(thickness 0.15)
				)
				(justify left bottom)
				(hide yes)
			)
		)
		(property "Description" ""
			(at 177.8 53.34 0)
			(effects
				(font
					(size 1.27 1.27)
				)
				(hide yes)
			)
		)
		(property "Author" "Antmicro"
			(at 193.04 55.88 0)
			(effects
				(font
					(size 1.27 1.27)
					(thickness 0.15)
				)
				(justify left bottom)
				(hide yes)
			)
		)
		(property "License" "Apache-2.0"
			(at 193.04 58.42 0)
			(effects
				(font
					(size 1.27 1.27)
					(thickness 0.15)
				)
				(justify left bottom)
				(hide yes)
			)
		)
		(pin "1"
		)
		(instances
			(project "data-center-rdimm-ddr5-tester"
				(path ""
					(reference "#PWR0218")
					(unit 1)
				)
			)
		)
	)
	(symbol
		(lib_id "antmicroCapacitors0402:C_100n_0402")
		(at 254 229.87 0)
		(mirror x)
		(unit 1)
		(exclude_from_sim no)
		(in_bom yes)
		(on_board yes)
		(dnp no)
		(property "Reference" "C132"
			(at 256.5336 224.155 0)
			(effects
				(font
					(size 1.27 1.27)
				)
			)
		)
		(property "Value" "C_100n_0402"
			(at 274.32 219.71 0)
			(effects
				(font
					(size 1.27 1.27)
					(thickness 0.15)
				)
				(justify left bottom)
				(hide yes)
			)
		)
		(property "Footprint" "antmicro-footprints:C_0402_1005Metric"
			(at 274.32 217.17 0)
			(effects
				(font
					(size 1.27 1.27)
					(thickness 0.15)
				)
				(justify left bottom)
				(hide yes)
			)
		)
		(property "Datasheet" "https://www.murata.com/products/productdetail?partno=GRM155R61H104KE14%23"
			(at 274.32 214.63 0)
			(effects
				(font
					(size 1.27 1.27)
					(thickness 0.15)
				)
				(justify left bottom)
				(hide yes)
			)
		)
		(property "Description" ""
			(at 254 229.87 0)
			(effects
				(font
					(size 1.27 1.27)
				)
				(hide yes)
			)
		)
		(property "Manufacturer" "Murata"
			(at 274.32 209.55 0)
			(effects
				(font
					(size 1.27 1.27)
					(thickness 0.15)
				)
				(justify left bottom)
				(hide yes)
			)
		)
		(property "MPN" "GRM155R61H104KE14D"
			(at 274.32 212.09 0)
			(effects
				(font
					(size 1.27 1.27)
					(thickness 0.15)
				)
				(justify left bottom)
				(hide yes)
			)
		)
		(property "Val" "100n"
			(at 256.54 226.695 0)
			(effects
				(font
					(size 1.27 1.27)
					(thickness 0.15)
				)
			)
		)
		(property "License" "Apache-2.0"
			(at 274.32 207.01 0)
			(effects
				(font
					(size 1.27 1.27)
					(thickness 0.15)
				)
				(justify left bottom)
				(hide yes)
			)
		)
		(property "Author" "Antmicro"
			(at 274.32 204.47 0)
			(effects
				(font
					(size 1.27 1.27)
					(thickness 0.15)
				)
				(justify left bottom)
				(hide yes)
			)
		)
		(property "Voltage" "50V"
			(at 274.32 201.93 0)
			(effects
				(font
					(size 1.27 1.27)
				)
				(justify left bottom)
				(hide yes)
			)
		)
		(property "Dielectric" "X5R"
			(at 274.32 199.39 0)
			(effects
				(font
					(size 1.27 1.27)
				)
				(justify left bottom)
				(hide yes)
			)
		)
		(pin "1"
		)
		(pin "2"
		)
		(instances
			(project "data-center-rdimm-ddr5-tester"
				(path ""
					(reference "C132")
					(unit 1)
				)
			)
		)
	)
	(symbol
		(lib_id "antmicropower:+3V3")
		(at 190.5 63.5 0)
		(unit 1)
		(exclude_from_sim no)
		(in_bom yes)
		(on_board yes)
		(dnp no)
		(fields_autoplaced yes)
		(property "Reference" "#PWR0216"
			(at 205.74 63.5 0)
			(effects
				(font
					(size 1.27 1.27)
					(thickness 0.15)
				)
				(justify left bottom)
				(hide yes)
			)
		)
		(property "Value" "+3V3"
			(at 190.5 59.055 0)
			(effects
				(font
					(size 1.27 1.27)
					(thickness 0.15)
				)
			)
		)
		(property "Footprint" ""
			(at 205.74 71.12 0)
			(effects
				(font
					(size 1.27 1.27)
					(thickness 0.15)
				)
				(justify left bottom)
				(hide yes)
			)
		)
		(property "Datasheet" ""
			(at 205.74 73.66 0)
			(effects
				(font
					(size 1.27 1.27)
					(thickness 0.15)
				)
				(justify left bottom)
				(hide yes)
			)
		)
		(property "Description" ""
			(at 190.5 63.5 0)
			(effects
				(font
					(size 1.27 1.27)
				)
				(hide yes)
			)
		)
		(property "Author" "Antmicro"
			(at 205.74 66.04 0)
			(effects
				(font
					(size 1.27 1.27)
					(thickness 0.15)
				)
				(justify left bottom)
				(hide yes)
			)
		)
		(property "License" "Apache-2.0"
			(at 205.74 68.58 0)
			(effects
				(font
					(size 1.27 1.27)
					(thickness 0.15)
				)
				(justify left bottom)
				(hide yes)
			)
		)
		(pin "1"
		)
		(instances
			(project "data-center-rdimm-ddr5-tester"
				(path ""
					(reference "#PWR0216")
					(unit 1)
				)
			)
		)
	)
	(symbol
		(lib_id "antmicropower:GND")
		(at 306.07 207.01 0)
		(unit 1)
		(exclude_from_sim no)
		(in_bom yes)
		(on_board yes)
		(dnp no)
		(fields_autoplaced yes)
		(property "Reference" "#PWR0531"
			(at 306.07 213.36 0)
			(effects
				(font
					(size 1.27 1.27)
				)
				(hide yes)
			)
		)
		(property "Value" "GND"
			(at 304.165 211.455 0)
			(effects
				(font
					(size 1.27 1.27)
					(thickness 0.15)
				)
				(justify left bottom)
			)
		)
		(property "Footprint" ""
			(at 314.96 214.63 0)
			(effects
				(font
					(size 1.27 1.27)
					(thickness 0.15)
				)
				(justify left bottom)
				(hide yes)
			)
		)
		(property "Datasheet" ""
			(at 314.96 219.71 0)
			(effects
				(font
					(size 1.27 1.27)
					(thickness 0.15)
				)
				(justify left bottom)
				(hide yes)
			)
		)
		(property "Description" ""
			(at 306.07 207.01 0)
			(effects
				(font
					(size 1.27 1.27)
				)
				(hide yes)
			)
		)
		(property "Author" "Antmicro"
			(at 314.96 212.09 0)
			(effects
				(font
					(size 1.27 1.27)
					(thickness 0.15)
				)
				(justify left bottom)
				(hide yes)
			)
		)
		(property "License" "Apache-2.0"
			(at 314.96 214.63 0)
			(effects
				(font
					(size 1.27 1.27)
					(thickness 0.15)
				)
				(justify left bottom)
				(hide yes)
			)
		)
		(pin "1"
		)
		(instances
			(project "data-center-rdimm-ddr5-tester"
				(path ""
					(reference "#PWR0531")
					(unit 1)
				)
			)
		)
	)
	(symbol
		(lib_id "antmicropower:GND")
		(at 389.89 102.87 0)
		(mirror y)
		(unit 1)
		(exclude_from_sim no)
		(in_bom yes)
		(on_board yes)
		(dnp no)
		(fields_autoplaced yes)
		(property "Reference" "#PWR040"
			(at 389.89 109.22 0)
			(effects
				(font
					(size 1.27 1.27)
				)
				(hide yes)
			)
		)
		(property "Value" "GND"
			(at 391.795 107.315 0)
			(effects
				(font
					(size 1.27 1.27)
					(thickness 0.15)
				)
				(justify left bottom)
			)
		)
		(property "Footprint" ""
			(at 381 110.49 0)
			(effects
				(font
					(size 1.27 1.27)
					(thickness 0.15)
				)
				(justify left bottom)
				(hide yes)
			)
		)
		(property "Datasheet" ""
			(at 381 115.57 0)
			(effects
				(font
					(size 1.27 1.27)
					(thickness 0.15)
				)
				(justify left bottom)
				(hide yes)
			)
		)
		(property "Description" ""
			(at 389.89 102.87 0)
			(effects
				(font
					(size 1.27 1.27)
				)
				(hide yes)
			)
		)
		(property "Author" "Antmicro"
			(at 381 107.95 0)
			(effects
				(font
					(size 1.27 1.27)
					(thickness 0.15)
				)
				(justify left bottom)
				(hide yes)
			)
		)
		(property "License" "Apache-2.0"
			(at 381 110.49 0)
			(effects
				(font
					(size 1.27 1.27)
					(thickness 0.15)
				)
				(justify left bottom)
				(hide yes)
			)
		)
		(pin "1"
		)
		(instances
			(project "data-center-rdimm-ddr5-tester"
				(path ""
					(reference "#PWR040")
					(unit 1)
				)
			)
		)
	)
	(symbol
		(lib_id "antmicroResistors0402:R_64k9_0402")
		(at 39.37 271.78 180)
		(unit 1)
		(exclude_from_sim no)
		(in_bom no)
		(on_board yes)
		(dnp yes)
		(property "Reference" "R228"
			(at 39.37 270.51 0)
			(effects
				(font
					(size 1.27 1.27)
					(thickness 0.15)
				)
				(justify right)
			)
		)
		(property "Value" "R_64k9_0402"
			(at 19.05 259.08 0)
			(effects
				(font
					(size 1.27 1.27)
					(thickness 0.15)
				)
				(justify left bottom)
				(hide yes)
			)
		)
		(property "Footprint" "antmicro-footprints:R_0402_1005Metric"
			(at 19.05 256.54 0)
			(effects
				(font
					(size 1.27 1.27)
					(thickness 0.15)
				)
				(justify left bottom)
				(hide yes)
			)
		)
		(property "Datasheet" "https://www.bourns.com/docs/product-datasheets/cr.pdf"
			(at 19.05 254 0)
			(effects
				(font
					(size 1.27 1.27)
					(thickness 0.15)
				)
				(justify left bottom)
				(hide yes)
			)
		)
		(property "Description" ""
			(at 39.37 271.78 0)
			(effects
				(font
					(size 1.27 1.27)
				)
				(hide yes)
			)
		)
		(property "MPN" "CR0402-FX-6492GLF"
			(at 19.05 251.46 0)
			(effects
				(font
					(size 1.27 1.27)
					(thickness 0.15)
				)
				(justify left bottom)
				(hide yes)
			)
		)
		(property "Manufacturer" "Bourns"
			(at 19.05 248.92 0)
			(effects
				(font
					(size 1.27 1.27)
					(thickness 0.15)
				)
				(justify left bottom)
				(hide yes)
			)
		)
		(property "License" "Apache-2.0"
			(at 19.05 246.38 0)
			(effects
				(font
					(size 1.27 1.27)
					(thickness 0.15)
				)
				(justify left bottom)
				(hide yes)
			)
		)
		(property "Author" "Antmicro"
			(at 19.05 243.84 0)
			(effects
				(font
					(size 1.27 1.27)
					(thickness 0.15)
				)
				(justify left bottom)
				(hide yes)
			)
		)
		(property "Val" "64k9"
			(at 29.21 270.51 0)
			(effects
				(font
					(size 1.27 1.27)
					(thickness 0.15)
				)
				(justify right)
			)
		)
		(property "Tolerance" "1%"
			(at 19.05 261.62 0)
			(effects
				(font
					(size 1.27 1.27)
				)
				(justify left bottom)
				(hide yes)
			)
		)
		(pin "2"
		)
		(pin "1"
		)
		(instances
			(project "data-center-rdimm-ddr5-tester"
				(path ""
					(reference "R228")
					(unit 1)
				)
			)
		)
	)
	(symbol
		(lib_id "antmicroResistors0402:R_10k_0402")
		(at 354.33 107.95 90)
		(unit 1)
		(exclude_from_sim no)
		(in_bom yes)
		(on_board yes)
		(dnp no)
		(fields_autoplaced yes)
		(property "Reference" "R86"
			(at 356.87 104.14 90)
			(effects
				(font
					(size 1.27 1.27)
					(thickness 0.15)
				)
				(justify right)
			)
		)
		(property "Value" "R_10k_0402"
			(at 367.03 87.63 0)
			(effects
				(font
					(size 1.27 1.27)
					(thickness 0.15)
				)
				(justify left bottom)
				(hide yes)
			)
		)
		(property "Footprint" "antmicro-footprints:R_0402_1005Metric"
			(at 369.57 87.63 0)
			(effects
				(font
					(size 1.27 1.27)
					(thickness 0.15)
				)
				(justify left bottom)
				(hide yes)
			)
		)
		(property "Datasheet" "https://www.bourns.com/docs/product-datasheets/cr.pdf"
			(at 372.11 87.63 0)
			(effects
				(font
					(size 1.27 1.27)
					(thickness 0.15)
				)
				(justify left bottom)
				(hide yes)
			)
		)
		(property "Description" ""
			(at 354.33 107.95 0)
			(effects
				(font
					(size 1.27 1.27)
				)
				(hide yes)
			)
		)
		(property "MPN" "CR0402-FX-1002GLF"
			(at 374.65 87.63 0)
			(effects
				(font
					(size 1.27 1.27)
					(thickness 0.15)
				)
				(justify left bottom)
				(hide yes)
			)
		)
		(property "Manufacturer" "Bourns"
			(at 377.19 87.63 0)
			(effects
				(font
					(size 1.27 1.27)
					(thickness 0.15)
				)
				(justify left bottom)
				(hide yes)
			)
		)
		(property "License" "Apache-2.0"
			(at 379.73 87.63 0)
			(effects
				(font
					(size 1.27 1.27)
					(thickness 0.15)
				)
				(justify left bottom)
				(hide yes)
			)
		)
		(property "Author" "Antmicro"
			(at 382.27 87.63 0)
			(effects
				(font
					(size 1.27 1.27)
					(thickness 0.15)
				)
				(justify left bottom)
				(hide yes)
			)
		)
		(property "Val" "10k"
			(at 356.87 106.68 90)
			(effects
				(font
					(size 1.27 1.27)
					(thickness 0.15)
				)
				(justify right)
			)
		)
		(property "Tolerance" "1%"
			(at 364.49 87.63 0)
			(effects
				(font
					(size 1.27 1.27)
				)
				(justify left bottom)
				(hide yes)
			)
		)
		(pin "1"
		)
		(pin "2"
		)
		(instances
			(project "data-center-rdimm-ddr5-tester"
				(path ""
					(reference "R86")
					(unit 1)
				)
			)
		)
	)
	(symbol
		(lib_id "antmicroResistors0402:R_10k_0402")
		(at 102.87 114.3 90)
		(unit 1)
		(exclude_from_sim no)
		(in_bom yes)
		(on_board yes)
		(dnp no)
		(fields_autoplaced yes)
		(property "Reference" "R80"
			(at 106.68 110.49 90)
			(effects
				(font
					(size 1.27 1.27)
					(thickness 0.15)
				)
				(justify right)
			)
		)
		(property "Value" "R_10k_0402"
			(at 115.57 93.98 0)
			(effects
				(font
					(size 1.27 1.27)
					(thickness 0.15)
				)
				(justify left bottom)
				(hide yes)
			)
		)
		(property "Footprint" "antmicro-footprints:R_0402_1005Metric"
			(at 118.11 93.98 0)
			(effects
				(font
					(size 1.27 1.27)
					(thickness 0.15)
				)
				(justify left bottom)
				(hide yes)
			)
		)
		(property "Datasheet" "https://www.bourns.com/docs/product-datasheets/cr.pdf"
			(at 120.65 93.98 0)
			(effects
				(font
					(size 1.27 1.27)
					(thickness 0.15)
				)
				(justify left bottom)
				(hide yes)
			)
		)
		(property "Description" ""
			(at 102.87 114.3 0)
			(effects
				(font
					(size 1.27 1.27)
				)
				(hide yes)
			)
		)
		(property "MPN" "CR0402-FX-1002GLF"
			(at 123.19 93.98 0)
			(effects
				(font
					(size 1.27 1.27)
					(thickness 0.15)
				)
				(justify left bottom)
				(hide yes)
			)
		)
		(property "Manufacturer" "Bourns"
			(at 125.73 93.98 0)
			(effects
				(font
					(size 1.27 1.27)
					(thickness 0.15)
				)
				(justify left bottom)
				(hide yes)
			)
		)
		(property "License" "Apache-2.0"
			(at 128.27 93.98 0)
			(effects
				(font
					(size 1.27 1.27)
					(thickness 0.15)
				)
				(justify left bottom)
				(hide yes)
			)
		)
		(property "Author" "Antmicro"
			(at 130.81 93.98 0)
			(effects
				(font
					(size 1.27 1.27)
					(thickness 0.15)
				)
				(justify left bottom)
				(hide yes)
			)
		)
		(property "Val" "10k"
			(at 106.68 113.03 90)
			(effects
				(font
					(size 1.27 1.27)
					(thickness 0.15)
				)
				(justify right)
			)
		)
		(property "Tolerance" "1%"
			(at 113.03 93.98 0)
			(effects
				(font
					(size 1.27 1.27)
				)
				(justify left bottom)
				(hide yes)
			)
		)
		(pin "2"
		)
		(pin "1"
		)
		(instances
			(project "data-center-rdimm-ddr5-tester"
				(path ""
					(reference "R80")
					(unit 1)
				)
			)
		)
	)
	(symbol
		(lib_id "antmicroResistors0402:R_64k9_0402")
		(at 39.37 269.24 180)
		(unit 1)
		(exclude_from_sim no)
		(in_bom no)
		(on_board yes)
		(dnp yes)
		(property "Reference" "R227"
			(at 39.37 267.97 0)
			(effects
				(font
					(size 1.27 1.27)
					(thickness 0.15)
				)
				(justify right)
			)
		)
		(property "Value" "R_64k9_0402"
			(at 19.05 256.54 0)
			(effects
				(font
					(size 1.27 1.27)
					(thickness 0.15)
				)
				(justify left bottom)
				(hide yes)
			)
		)
		(property "Footprint" "antmicro-footprints:R_0402_1005Metric"
			(at 19.05 254 0)
			(effects
				(font
					(size 1.27 1.27)
					(thickness 0.15)
				)
				(justify left bottom)
				(hide yes)
			)
		)
		(property "Datasheet" "https://www.bourns.com/docs/product-datasheets/cr.pdf"
			(at 19.05 251.46 0)
			(effects
				(font
					(size 1.27 1.27)
					(thickness 0.15)
				)
				(justify left bottom)
				(hide yes)
			)
		)
		(property "Description" ""
			(at 39.37 269.24 0)
			(effects
				(font
					(size 1.27 1.27)
				)
				(hide yes)
			)
		)
		(property "MPN" "CR0402-FX-6492GLF"
			(at 19.05 248.92 0)
			(effects
				(font
					(size 1.27 1.27)
					(thickness 0.15)
				)
				(justify left bottom)
				(hide yes)
			)
		)
		(property "Manufacturer" "Bourns"
			(at 19.05 246.38 0)
			(effects
				(font
					(size 1.27 1.27)
					(thickness 0.15)
				)
				(justify left bottom)
				(hide yes)
			)
		)
		(property "License" "Apache-2.0"
			(at 19.05 243.84 0)
			(effects
				(font
					(size 1.27 1.27)
					(thickness 0.15)
				)
				(justify left bottom)
				(hide yes)
			)
		)
		(property "Author" "Antmicro"
			(at 19.05 241.3 0)
			(effects
				(font
					(size 1.27 1.27)
					(thickness 0.15)
				)
				(justify left bottom)
				(hide yes)
			)
		)
		(property "Val" "64k9"
			(at 29.21 267.97 0)
			(effects
				(font
					(size 1.27 1.27)
					(thickness 0.15)
				)
				(justify right)
			)
		)
		(property "Tolerance" "1%"
			(at 19.05 259.08 0)
			(effects
				(font
					(size 1.27 1.27)
				)
				(justify left bottom)
				(hide yes)
			)
		)
		(pin "2"
		)
		(pin "1"
		)
		(instances
			(project "data-center-rdimm-ddr5-tester"
				(path ""
					(reference "R227")
					(unit 1)
				)
			)
		)
	)
	(symbol
		(lib_id "antmicropower:+3V3")
		(at 109.22 259.08 0)
		(unit 1)
		(exclude_from_sim no)
		(in_bom yes)
		(on_board yes)
		(dnp no)
		(property "Reference" "#PWR0457"
			(at 124.46 259.08 0)
			(effects
				(font
					(size 1.27 1.27)
					(thickness 0.15)
				)
				(justify left bottom)
				(hide yes)
			)
		)
		(property "Value" "+3V3"
			(at 106.68 255.27 0)
			(effects
				(font
					(size 1.27 1.27)
					(thickness 0.15)
				)
				(justify left)
			)
		)
		(property "Footprint" ""
			(at 124.46 266.7 0)
			(effects
				(font
					(size 1.27 1.27)
					(thickness 0.15)
				)
				(justify left bottom)
				(hide yes)
			)
		)
		(property "Datasheet" ""
			(at 124.46 269.24 0)
			(effects
				(font
					(size 1.27 1.27)
					(thickness 0.15)
				)
				(justify left bottom)
				(hide yes)
			)
		)
		(property "Description" ""
			(at 109.22 259.08 0)
			(effects
				(font
					(size 1.27 1.27)
				)
				(hide yes)
			)
		)
		(property "Author" "Antmicro"
			(at 124.46 261.62 0)
			(effects
				(font
					(size 1.27 1.27)
					(thickness 0.15)
				)
				(justify left bottom)
				(hide yes)
			)
		)
		(property "License" "Apache-2.0"
			(at 124.46 264.16 0)
			(effects
				(font
					(size 1.27 1.27)
					(thickness 0.15)
				)
				(justify left bottom)
				(hide yes)
			)
		)
		(pin "1"
		)
		(instances
			(project "data-center-rdimm-ddr5-tester"
				(path ""
					(reference "#PWR0457")
					(unit 1)
				)
			)
		)
	)
	(symbol
		(lib_id "antmicropower:GND")
		(at 311.15 110.49 0)
		(mirror y)
		(unit 1)
		(exclude_from_sim no)
		(in_bom yes)
		(on_board yes)
		(dnp no)
		(fields_autoplaced yes)
		(property "Reference" "#PWR0470"
			(at 311.15 116.84 0)
			(effects
				(font
					(size 1.27 1.27)
				)
				(hide yes)
			)
		)
		(property "Value" "GND"
			(at 313.055 114.935 0)
			(effects
				(font
					(size 1.27 1.27)
					(thickness 0.15)
				)
				(justify left bottom)
			)
		)
		(property "Footprint" ""
			(at 302.26 118.11 0)
			(effects
				(font
					(size 1.27 1.27)
					(thickness 0.15)
				)
				(justify left bottom)
				(hide yes)
			)
		)
		(property "Datasheet" ""
			(at 302.26 123.19 0)
			(effects
				(font
					(size 1.27 1.27)
					(thickness 0.15)
				)
				(justify left bottom)
				(hide yes)
			)
		)
		(property "Description" ""
			(at 311.15 110.49 0)
			(effects
				(font
					(size 1.27 1.27)
				)
				(hide yes)
			)
		)
		(property "Author" "Antmicro"
			(at 302.26 115.57 0)
			(effects
				(font
					(size 1.27 1.27)
					(thickness 0.15)
				)
				(justify left bottom)
				(hide yes)
			)
		)
		(property "License" "Apache-2.0"
			(at 302.26 118.11 0)
			(effects
				(font
					(size 1.27 1.27)
					(thickness 0.15)
				)
				(justify left bottom)
				(hide yes)
			)
		)
		(pin "1"
		)
		(instances
			(project "data-center-rdimm-ddr5-tester"
				(path ""
					(reference "#PWR0470")
					(unit 1)
				)
			)
		)
	)
	(symbol
		(lib_id "antmicroCapacitors0402:C_10u_10V_0402")
		(at 119.38 269.24 90)
		(unit 1)
		(exclude_from_sim no)
		(in_bom yes)
		(on_board yes)
		(dnp no)
		(property "Reference" "C277"
			(at 118.11 267.97 0)
			(effects
				(font
					(size 1.27 1.27)
					(thickness 0.15)
				)
				(justify right)
			)
		)
		(property "Value" "C_10u_10V_0402"
			(at 129.54 248.92 0)
			(effects
				(font
					(size 1.27 1.27)
					(thickness 0.15)
				)
				(justify left bottom)
				(hide yes)
			)
		)
		(property "Footprint" "antmicro-footprints:C_0402_1005Metric"
			(at 132.08 248.92 0)
			(effects
				(font
					(size 1.27 1.27)
					(thickness 0.15)
				)
				(justify left bottom)
				(hide yes)
			)
		)
		(property "Datasheet" "https://www.murata.com/products/productdetail?partno=GRM155R61A106ME11%23"
			(at 134.62 248.92 0)
			(effects
				(font
					(size 1.27 1.27)
					(thickness 0.15)
				)
				(justify left bottom)
				(hide yes)
			)
		)
		(property "Description" ""
			(at 119.38 269.24 0)
			(effects
				(font
					(size 1.27 1.27)
				)
				(hide yes)
			)
		)
		(property "MPN" "GRM155R61A106ME11D"
			(at 137.16 248.92 0)
			(effects
				(font
					(size 1.27 1.27)
					(thickness 0.15)
				)
				(justify left bottom)
				(hide yes)
			)
		)
		(property "Manufacturer" "Murata"
			(at 139.7 248.92 0)
			(effects
				(font
					(size 1.27 1.27)
					(thickness 0.15)
				)
				(justify left bottom)
				(hide yes)
			)
		)
		(property "License" "Apache-2.0"
			(at 142.24 248.92 0)
			(effects
				(font
					(size 1.27 1.27)
					(thickness 0.15)
				)
				(justify left bottom)
				(hide yes)
			)
		)
		(property "Author" "Antmicro"
			(at 144.78 248.92 0)
			(effects
				(font
					(size 1.27 1.27)
					(thickness 0.15)
				)
				(justify left bottom)
				(hide yes)
			)
		)
		(property "Val" "10u"
			(at 118.11 261.62 0)
			(effects
				(font
					(size 1.27 1.27)
					(thickness 0.15)
				)
				(justify right)
			)
		)
		(property "Voltage" "10V"
			(at 147.32 248.92 0)
			(effects
				(font
					(size 1.27 1.27)
				)
				(justify left bottom)
				(hide yes)
			)
		)
		(property "Dielectric" "X5R"
			(at 149.86 248.92 0)
			(effects
				(font
					(size 1.27 1.27)
				)
				(justify left bottom)
				(hide yes)
			)
		)
		(property "Public" ""
			(at 152.4 248.92 0)
			(effects
				(font
					(size 1.27 1.27)
				)
				(justify left bottom)
				(hide yes)
			)
		)
		(pin "1"
		)
		(pin "2"
		)
		(instances
			(project "data-center-rdimm-ddr5-tester"
				(path ""
					(reference "C277")
					(unit 1)
				)
			)
		)
	)
	(symbol
		(lib_id "antmicroPMICPowerDistributionSwitchesLoadDrivers:TPS2116DRLR")
		(at 69.85 113.03 0)
		(unit 1)
		(exclude_from_sim no)
		(in_bom yes)
		(on_board yes)
		(dnp no)
		(fields_autoplaced yes)
		(property "Reference" "U43"
			(at 78.74 106.68 0)
			(effects
				(font
					(size 1.27 1.27)
					(thickness 0.15)
				)
			)
		)
		(property "Value" "TPS2116DRLR"
			(at 104.14 115.57 0)
			(effects
				(font
					(size 1.27 1.27)
					(thickness 0.15)
				)
				(justify left bottom)
				(hide yes)
			)
		)
		(property "Footprint" "antmicro-footprints:SOT-583"
			(at 104.14 118.11 0)
			(effects
				(font
					(size 1.27 1.27)
					(thickness 0.15)
				)
				(justify left bottom)
				(hide yes)
			)
		)
		(property "Datasheet" "https://www.ti.com/lit/ds/symlink/tps2116.pdf?ts=1647438832100&ref_url=https%253A%252F%252Fwww.ti.com%252Fproduct%252FTPS2116"
			(at 104.14 120.65 0)
			(effects
				(font
					(size 1.27 1.27)
					(thickness 0.15)
				)
				(justify left bottom)
				(hide yes)
			)
		)
		(property "Description" ""
			(at 69.85 113.03 0)
			(effects
				(font
					(size 1.27 1.27)
				)
				(hide yes)
			)
		)
		(property "Manufacturer" "Texas Instruments"
			(at 104.14 123.19 0)
			(effects
				(font
					(size 1.27 1.27)
					(thickness 0.15)
				)
				(justify left bottom)
				(hide yes)
			)
		)
		(property "MPN" "TPS2116DRLR"
			(at 78.74 109.22 0)
			(effects
				(font
					(size 1.27 1.27)
					(thickness 0.15)
				)
			)
		)
		(property "Author" "Antmicro"
			(at 104.14 128.27 0)
			(effects
				(font
					(size 1.27 1.27)
					(thickness 0.15)
				)
				(justify left bottom)
				(hide yes)
			)
		)
		(property "License" "Apache-2.0"
			(at 104.14 130.81 0)
			(effects
				(font
					(size 1.27 1.27)
					(thickness 0.15)
				)
				(justify left bottom)
				(hide yes)
			)
		)
		(pin "7"
		)
		(pin "1"
		)
		(pin "5"
		)
		(pin "3"
		)
		(pin "6"
		)
		(pin "4"
		)
		(pin "2"
		)
		(pin "8"
		)
		(instances
			(project "data-center-rdimm-ddr5-tester"
				(path ""
					(reference "U43")
					(unit 1)
				)
			)
		)
	)
	(symbol
		(lib_id "antmicropower:GND")
		(at 57.15 234.95 0)
		(unit 1)
		(exclude_from_sim no)
		(in_bom yes)
		(on_board yes)
		(dnp no)
		(fields_autoplaced yes)
		(property "Reference" "#PWR0461"
			(at 66.04 237.49 0)
			(effects
				(font
					(size 1.27 1.27)
					(thickness 0.15)
				)
				(justify left bottom)
				(hide yes)
			)
		)
		(property "Value" "GND"
			(at 57.15 239.395 0)
			(effects
				(font
					(size 1.27 1.27)
					(thickness 0.15)
				)
			)
		)
		(property "Footprint" ""
			(at 66.04 242.57 0)
			(effects
				(font
					(size 1.27 1.27)
					(thickness 0.15)
				)
				(justify left bottom)
				(hide yes)
			)
		)
		(property "Datasheet" ""
			(at 66.04 247.65 0)
			(effects
				(font
					(size 1.27 1.27)
					(thickness 0.15)
				)
				(justify left bottom)
				(hide yes)
			)
		)
		(property "Description" ""
			(at 57.15 234.95 0)
			(effects
				(font
					(size 1.27 1.27)
				)
				(hide yes)
			)
		)
		(property "Author" "Antmicro"
			(at 66.04 242.57 0)
			(effects
				(font
					(size 1.27 1.27)
					(thickness 0.15)
				)
				(justify left bottom)
				(hide yes)
			)
		)
		(property "License" "Apache-2.0"
			(at 66.04 245.11 0)
			(effects
				(font
					(size 1.27 1.27)
					(thickness 0.15)
				)
				(justify left bottom)
				(hide yes)
			)
		)
		(pin "1"
		)
		(instances
			(project "data-center-rdimm-ddr5-tester"
				(path ""
					(reference "#PWR0461")
					(unit 1)
				)
			)
		)
	)
	(symbol
		(lib_id "antmicroFerriteBeadsandChips:FB_120Z_2A_Murata-BLM18PG_0603")
		(at 166.37 215.9 0)
		(unit 1)
		(exclude_from_sim no)
		(in_bom yes)
		(on_board yes)
		(dnp no)
		(fields_autoplaced yes)
		(property "Reference" "FB3"
			(at 168.8719 210.505 0)
			(effects
				(font
					(size 1.27 1.27)
					(thickness 0.15)
				)
			)
		)
		(property "Value" "FB_120Z_2A_Murata-BLM18PG_0603"
			(at 181.61 218.44 0)
			(effects
				(font
					(size 1.27 1.27)
					(thickness 0.15)
				)
				(justify left bottom)
				(hide yes)
			)
		)
		(property "Footprint" "antmicro-footprints:FB_0603_1608Metric"
			(at 181.61 223.52 0)
			(effects
				(font
					(size 1.27 1.27)
					(thickness 0.15)
				)
				(justify left bottom)
				(hide yes)
			)
		)
		(property "Datasheet" "https://www.murata.com/en-us/products/productdata/8796738650142/ENFA0003.pdf"
			(at 181.61 226.06 0)
			(effects
				(font
					(size 1.27 1.27)
					(thickness 0.15)
				)
				(justify left bottom)
				(hide yes)
			)
		)
		(property "Description" ""
			(at 166.37 215.9 0)
			(effects
				(font
					(size 1.27 1.27)
				)
				(hide yes)
			)
		)
		(property "Val" "120Z/2A"
			(at 168.8719 213.0353 0)
			(effects
				(font
					(size 1.27 1.27)
				)
			)
		)
		(property "MPN" "BLM18PG121SN1D"
			(at 181.61 228.6 0)
			(effects
				(font
					(size 1.27 1.27)
					(thickness 0.15)
				)
				(justify left bottom)
				(hide yes)
			)
		)
		(property "Manufacturer" "Murata"
			(at 181.61 231.14 0)
			(effects
				(font
					(size 1.27 1.27)
					(thickness 0.15)
				)
				(justify left bottom)
				(hide yes)
			)
		)
		(property "Author" "Antmicro"
			(at 181.61 233.68 0)
			(effects
				(font
					(size 1.27 1.27)
					(thickness 0.15)
				)
				(justify left bottom)
				(hide yes)
			)
		)
		(property "License" "Apache-2.0"
			(at 181.61 236.22 0)
			(effects
				(font
					(size 1.27 1.27)
					(thickness 0.15)
				)
				(justify left bottom)
				(hide yes)
			)
		)
		(pin "1"
		)
		(pin "2"
		)
		(instances
			(project "data-center-rdimm-ddr5-tester"
				(path ""
					(reference "FB3")
					(unit 1)
				)
			)
		)
	)
	(symbol
		(lib_id "antmicroResistors0402:R_100k_0402")
		(at 300.99 110.49 90)
		(unit 1)
		(exclude_from_sim no)
		(in_bom yes)
		(on_board yes)
		(dnp no)
		(property "Reference" "R83"
			(at 299.72 106.68 90)
			(effects
				(font
					(size 1.27 1.27)
					(thickness 0.15)
				)
				(justify left)
			)
		)
		(property "Value" "R_100k_0402"
			(at 313.69 90.17 0)
			(effects
				(font
					(size 1.27 1.27)
					(thickness 0.15)
				)
				(justify left bottom)
				(hide yes)
			)
		)
		(property "Footprint" "antmicro-footprints:R_0402_1005Metric"
			(at 316.23 90.17 0)
			(effects
				(font
					(size 1.27 1.27)
					(thickness 0.15)
				)
				(justify left bottom)
				(hide yes)
			)
		)
		(property "Datasheet" "https://www.bourns.com/docs/product-datasheets/cr.pdf"
			(at 318.77 90.17 0)
			(effects
				(font
					(size 1.27 1.27)
					(thickness 0.15)
				)
				(justify left bottom)
				(hide yes)
			)
		)
		(property "Description" ""
			(at 300.99 110.49 0)
			(effects
				(font
					(size 1.27 1.27)
				)
				(hide yes)
			)
		)
		(property "MPN" "CR0402-FX-1003GLF"
			(at 321.31 90.17 0)
			(effects
				(font
					(size 1.27 1.27)
					(thickness 0.15)
				)
				(justify left bottom)
				(hide yes)
			)
		)
		(property "Manufacturer" "Bourns"
			(at 323.85 90.17 0)
			(effects
				(font
					(size 1.27 1.27)
					(thickness 0.15)
				)
				(justify left bottom)
				(hide yes)
			)
		)
		(property "License" "Apache-2.0"
			(at 326.39 90.17 0)
			(effects
				(font
					(size 1.27 1.27)
					(thickness 0.15)
				)
				(justify left bottom)
				(hide yes)
			)
		)
		(property "Author" "Antmicro"
			(at 328.93 90.17 0)
			(effects
				(font
					(size 1.27 1.27)
					(thickness 0.15)
				)
				(justify left bottom)
				(hide yes)
			)
		)
		(property "Val" "100k"
			(at 299.72 109.22 90)
			(effects
				(font
					(size 1.27 1.27)
					(thickness 0.15)
				)
				(justify left)
			)
		)
		(property "Tolerance" "1%"
			(at 311.15 90.17 0)
			(effects
				(font
					(size 1.27 1.27)
				)
				(justify left bottom)
				(hide yes)
			)
		)
		(pin "1"
		)
		(pin "2"
		)
		(instances
			(project "data-center-rdimm-ddr5-tester"
				(path ""
					(reference "R83")
					(unit 1)
				)
			)
		)
	)
	(symbol
		(lib_id "antmicroFixedInductors:L_20n_0.35A_0402")
		(at 370.84 45.72 90)
		(unit 1)
		(exclude_from_sim no)
		(in_bom yes)
		(on_board yes)
		(dnp no)
		(property "Reference" "L3"
			(at 372.11 41.91 90)
			(effects
				(font
					(size 1.27 1.27)
					(thickness 0.15)
				)
				(justify right)
			)
		)
		(property "Value" "L_20n_0.35A_0402"
			(at 373.38 31.75 0)
			(effects
				(font
					(size 1.27 1.27)
					(thickness 0.15)
				)
				(justify left bottom)
				(hide yes)
			)
		)
		(property "Footprint" "antmicro-footprints:L_0402_1005Metric"
			(at 378.46 31.75 0)
			(effects
				(font
					(size 1.27 1.27)
					(thickness 0.15)
				)
				(justify left bottom)
				(hide yes)
			)
		)
		(property "Datasheet" "https://product.tdk.com/system/files/dam/doc/product/inductor/inductor/smd/catalog/inductor_automotive_high-frequency_mlg1005s_en.pdf?ref_disty=mouser"
			(at 381 31.75 0)
			(effects
				(font
					(size 1.27 1.27)
					(thickness 0.15)
				)
				(justify left bottom)
				(hide yes)
			)
		)
		(property "Description" ""
			(at 370.84 45.72 0)
			(effects
				(font
					(size 1.27 1.27)
				)
				(hide yes)
			)
		)
		(property "Val" "20n/0.35A"
			(at 368.3 40.005 0)
			(effects
				(font
					(size 1.27 1.27)
					(thickness 0.15)
				)
				(justify right)
			)
		)
		(property "Manufacturer" "TDK"
			(at 383.54 31.75 0)
			(effects
				(font
					(size 1.27 1.27)
					(thickness 0.15)
				)
				(justify left bottom)
				(hide yes)
			)
		)
		(property "MPN" "MLG1005S20NJTD25"
			(at 386.08 31.75 0)
			(effects
				(font
					(size 1.27 1.27)
					(thickness 0.15)
				)
				(justify left bottom)
				(hide yes)
			)
		)
		(property "ISat" ""
			(at 387.35 31.75 0)
			(effects
				(font
					(size 1.27 1.27)
				)
				(justify left)
				(hide yes)
			)
		)
		(property "IMax" "0.35 A"
			(at 391.16 31.75 0)
			(effects
				(font
					(size 1.27 1.27)
					(thickness 0.15)
				)
				(justify left bottom)
				(hide yes)
			)
		)
		(property "Size" "1.0x0.5"
			(at 393.7 31.75 0)
			(effects
				(font
					(size 1.27 1.27)
					(thickness 0.15)
				)
				(justify left bottom)
				(hide yes)
			)
		)
		(property "Author" "Antmicro"
			(at 396.24 31.75 0)
			(effects
				(font
					(size 1.27 1.27)
					(thickness 0.15)
				)
				(justify left bottom)
				(hide yes)
			)
		)
		(property "License" "Apache-2.0"
			(at 398.78 31.75 0)
			(effects
				(font
					(size 1.27 1.27)
					(thickness 0.15)
				)
				(justify left bottom)
				(hide yes)
			)
		)
		(pin "2"
		)
		(pin "1"
		)
		(instances
			(project "data-center-rdimm-ddr5-tester"
				(path ""
					(reference "L3")
					(unit 1)
				)
			)
		)
	)
	(symbol
		(lib_id "antmicropower:GND")
		(at 340.36 208.28 0)
		(unit 1)
		(exclude_from_sim no)
		(in_bom yes)
		(on_board yes)
		(dnp no)
		(fields_autoplaced yes)
		(property "Reference" "#PWR0526"
			(at 340.36 214.63 0)
			(effects
				(font
					(size 1.27 1.27)
				)
				(hide yes)
			)
		)
		(property "Value" "GND"
			(at 338.455 212.725 0)
			(effects
				(font
					(size 1.27 1.27)
					(thickness 0.15)
				)
				(justify left bottom)
			)
		)
		(property "Footprint" ""
			(at 349.25 215.9 0)
			(effects
				(font
					(size 1.27 1.27)
					(thickness 0.15)
				)
				(justify left bottom)
				(hide yes)
			)
		)
		(property "Datasheet" ""
			(at 349.25 220.98 0)
			(effects
				(font
					(size 1.27 1.27)
					(thickness 0.15)
				)
				(justify left bottom)
				(hide yes)
			)
		)
		(property "Description" ""
			(at 340.36 208.28 0)
			(effects
				(font
					(size 1.27 1.27)
				)
				(hide yes)
			)
		)
		(property "Author" "Antmicro"
			(at 349.25 213.36 0)
			(effects
				(font
					(size 1.27 1.27)
					(thickness 0.15)
				)
				(justify left bottom)
				(hide yes)
			)
		)
		(property "License" "Apache-2.0"
			(at 349.25 215.9 0)
			(effects
				(font
					(size 1.27 1.27)
					(thickness 0.15)
				)
				(justify left bottom)
				(hide yes)
			)
		)
		(pin "1"
		)
		(instances
			(project "data-center-rdimm-ddr5-tester"
				(path ""
					(reference "#PWR0526")
					(unit 1)
				)
			)
		)
	)
	(symbol
		(lib_id "antmicropower:+1V8")
		(at 102.87 106.68 0)
		(unit 1)
		(exclude_from_sim no)
		(in_bom yes)
		(on_board yes)
		(dnp no)
		(fields_autoplaced yes)
		(property "Reference" "#PWR0494"
			(at 118.11 109.22 0)
			(effects
				(font
					(size 1.27 1.27)
					(thickness 0.15)
				)
				(justify left bottom)
				(hide yes)
			)
		)
		(property "Value" "+1V8"
			(at 102.87 102.87 0)
			(effects
				(font
					(size 1.27 1.27)
					(thickness 0.15)
				)
			)
		)
		(property "Footprint" ""
			(at 118.11 114.3 0)
			(effects
				(font
					(size 1.27 1.27)
					(thickness 0.15)
				)
				(justify left bottom)
				(hide yes)
			)
		)
		(property "Datasheet" ""
			(at 118.11 116.84 0)
			(effects
				(font
					(size 1.27 1.27)
					(thickness 0.15)
				)
				(justify left bottom)
				(hide yes)
			)
		)
		(property "Description" ""
			(at 102.87 106.68 0)
			(effects
				(font
					(size 1.27 1.27)
				)
				(hide yes)
			)
		)
		(property "Author" "Antmicro"
			(at 118.11 111.76 0)
			(effects
				(font
					(size 1.27 1.27)
					(thickness 0.15)
				)
				(justify left bottom)
				(hide yes)
			)
		)
		(property "License" "Apache-2.0"
			(at 118.11 114.3 0)
			(effects
				(font
					(size 1.27 1.27)
					(thickness 0.15)
				)
				(justify left bottom)
				(hide yes)
			)
		)
		(pin "1"
		)
		(instances
			(project "data-center-rdimm-ddr5-tester"
				(path ""
					(reference "#PWR0494")
					(unit 1)
				)
			)
		)
	)
	(symbol
		(lib_id "antmicroTVSDiodes:TPD4E05U06QDQARQ1")
		(at 387.35 233.68 0)
		(unit 1)
		(exclude_from_sim no)
		(in_bom yes)
		(on_board yes)
		(dnp no)
		(fields_autoplaced yes)
		(property "Reference" "U48"
			(at 393.065 226.695 0)
			(effects
				(font
					(size 1.27 1.27)
				)
			)
		)
		(property "Value" "TPD4E05U06QDQARQ1"
			(at 389.255 247.015 0)
			(effects
				(font
					(size 1.27 1.27)
					(thickness 0.15)
				)
				(justify left)
				(hide yes)
			)
		)
		(property "Footprint" "antmicro-footprints:USON-10_2.5x1mm_P0.5mm"
			(at 411.48 238.76 0)
			(effects
				(font
					(size 1.27 1.27)
					(thickness 0.15)
				)
				(justify left bottom)
				(hide yes)
			)
		)
		(property "Datasheet" "https://www.ti.com/lit/ds/symlink/tpd4e05u06-q1.pdf?HQS=dis-mous-null-mousermode-dsf-pf-null-wwe&ts=1663591265741&ref_url=https%253A%252F%252Fwww.mouser.com%252F"
			(at 411.48 241.3 0)
			(effects
				(font
					(size 1.27 1.27)
					(thickness 0.15)
				)
				(justify left bottom)
				(hide yes)
			)
		)
		(property "Description" ""
			(at 387.35 233.68 0)
			(effects
				(font
					(size 1.27 1.27)
				)
				(hide yes)
			)
		)
		(property "Manufacturer" "Texas Instruments"
			(at 411.48 243.84 0)
			(effects
				(font
					(size 1.27 1.27)
					(thickness 0.15)
				)
				(justify left bottom)
				(hide yes)
			)
		)
		(property "MPN" "TPD4E05U06QDQARQ1"
			(at 393.065 229.235 0)
			(effects
				(font
					(size 1.27 1.27)
					(thickness 0.15)
				)
			)
		)
		(property "Author" "Antmicro"
			(at 411.48 248.92 0)
			(effects
				(font
					(size 1.27 1.27)
					(thickness 0.15)
				)
				(justify left bottom)
				(hide yes)
			)
		)
		(property "License" "Apache-2.0"
			(at 411.48 251.46 0)
			(effects
				(font
					(size 1.27 1.27)
					(thickness 0.15)
				)
				(justify left bottom)
				(hide yes)
			)
		)
		(pin "1"
		)
		(pin "10"
		)
		(pin "2"
		)
		(pin "3"
		)
		(pin "4"
		)
		(pin "5"
		)
		(pin "6"
		)
		(pin "7"
		)
		(pin "8"
		)
		(pin "9"
		)
		(instances
			(project "data-center-rdimm-ddr5-tester"
				(path ""
					(reference "U48")
					(unit 1)
				)
			)
		)
	)
	(symbol
		(lib_id "antmicroResistors0402:R_49k9_0402")
		(at 328.93 38.1 90)
		(unit 1)
		(exclude_from_sim no)
		(in_bom yes)
		(on_board yes)
		(dnp no)
		(fields_autoplaced yes)
		(property "Reference" "R31"
			(at 330.835 34.29 90)
			(effects
				(font
					(size 1.27 1.27)
					(thickness 0.15)
				)
				(justify right)
			)
		)
		(property "Value" "R_49k9_0402"
			(at 341.63 17.78 0)
			(effects
				(font
					(size 1.27 1.27)
					(thickness 0.15)
				)
				(justify left bottom)
				(hide yes)
			)
		)
		(property "Footprint" "antmicro-footprints:R_0402_1005Metric"
			(at 344.17 17.78 0)
			(effects
				(font
					(size 1.27 1.27)
					(thickness 0.15)
				)
				(justify left bottom)
				(hide yes)
			)
		)
		(property "Datasheet" "https://www.bourns.com/docs/product-datasheets/cr.pdf"
			(at 346.71 17.78 0)
			(effects
				(font
					(size 1.27 1.27)
					(thickness 0.15)
				)
				(justify left bottom)
				(hide yes)
			)
		)
		(property "Description" ""
			(at 328.93 38.1 0)
			(effects
				(font
					(size 1.27 1.27)
				)
				(hide yes)
			)
		)
		(property "MPN" "CR0402-FX-4992GLF"
			(at 349.25 17.78 0)
			(effects
				(font
					(size 1.27 1.27)
					(thickness 0.15)
				)
				(justify left bottom)
				(hide yes)
			)
		)
		(property "Manufacturer" "Bourns"
			(at 351.79 17.78 0)
			(effects
				(font
					(size 1.27 1.27)
					(thickness 0.15)
				)
				(justify left bottom)
				(hide yes)
			)
		)
		(property "License" "Apache-2.0"
			(at 354.33 17.78 0)
			(effects
				(font
					(size 1.27 1.27)
					(thickness 0.15)
				)
				(justify left bottom)
				(hide yes)
			)
		)
		(property "Author" "Antmicro"
			(at 356.87 17.78 0)
			(effects
				(font
					(size 1.27 1.27)
					(thickness 0.15)
				)
				(justify left bottom)
				(hide yes)
			)
		)
		(property "Val" "49k9"
			(at 330.835 36.83 90)
			(effects
				(font
					(size 1.27 1.27)
					(thickness 0.15)
				)
				(justify right)
			)
		)
		(property "Tolerance" "1%"
			(at 339.09 17.78 0)
			(effects
				(font
					(size 1.27 1.27)
				)
				(justify left bottom)
				(hide yes)
			)
		)
		(pin "1"
		)
		(pin "2"
		)
		(instances
			(project "data-center-rdimm-ddr5-tester"
				(path ""
					(reference "R31")
					(unit 1)
				)
			)
		)
	)
	(symbol
		(lib_id "antmicropower:GND")
		(at 242.57 270.51 0)
		(unit 1)
		(exclude_from_sim no)
		(in_bom yes)
		(on_board yes)
		(dnp no)
		(property "Reference" "#PWR0173"
			(at 251.46 273.05 0)
			(effects
				(font
					(size 1.27 1.27)
					(thickness 0.15)
				)
				(justify left bottom)
				(hide yes)
			)
		)
		(property "Value" "GND"
			(at 242.57 274.32 0)
			(effects
				(font
					(size 1.27 1.27)
					(thickness 0.15)
				)
			)
		)
		(property "Footprint" ""
			(at 251.46 278.13 0)
			(effects
				(font
					(size 1.27 1.27)
					(thickness 0.15)
				)
				(justify left bottom)
				(hide yes)
			)
		)
		(property "Datasheet" ""
			(at 251.46 283.21 0)
			(effects
				(font
					(size 1.27 1.27)
					(thickness 0.15)
				)
				(justify left bottom)
				(hide yes)
			)
		)
		(property "Description" ""
			(at 242.57 270.51 0)
			(effects
				(font
					(size 1.27 1.27)
				)
				(hide yes)
			)
		)
		(property "Author" "Antmicro"
			(at 251.46 278.13 0)
			(effects
				(font
					(size 1.27 1.27)
					(thickness 0.15)
				)
				(justify left bottom)
				(hide yes)
			)
		)
		(property "License" "Apache-2.0"
			(at 251.46 280.67 0)
			(effects
				(font
					(size 1.27 1.27)
					(thickness 0.15)
				)
				(justify left bottom)
				(hide yes)
			)
		)
		(pin "1"
		)
		(instances
			(project "data-center-rdimm-ddr5-tester"
				(path ""
					(reference "#PWR0173")
					(unit 1)
				)
			)
		)
	)
	(symbol
		(lib_id "antmicroFixedInductors:L_20n_0.35A_0402")
		(at 378.46 45.72 90)
		(unit 1)
		(exclude_from_sim no)
		(in_bom yes)
		(on_board yes)
		(dnp no)
		(property "Reference" "L4"
			(at 379.73 41.91 90)
			(effects
				(font
					(size 1.27 1.27)
					(thickness 0.15)
				)
				(justify right)
			)
		)
		(property "Value" "L_20n_0.35A_0402"
			(at 381 31.75 0)
			(effects
				(font
					(size 1.27 1.27)
					(thickness 0.15)
				)
				(justify left bottom)
				(hide yes)
			)
		)
		(property "Footprint" "antmicro-footprints:L_0402_1005Metric"
			(at 386.08 31.75 0)
			(effects
				(font
					(size 1.27 1.27)
					(thickness 0.15)
				)
				(justify left bottom)
				(hide yes)
			)
		)
		(property "Datasheet" "https://product.tdk.com/system/files/dam/doc/product/inductor/inductor/smd/catalog/inductor_automotive_high-frequency_mlg1005s_en.pdf?ref_disty=mouser"
			(at 388.62 31.75 0)
			(effects
				(font
					(size 1.27 1.27)
					(thickness 0.15)
				)
				(justify left bottom)
				(hide yes)
			)
		)
		(property "Description" ""
			(at 378.46 45.72 0)
			(effects
				(font
					(size 1.27 1.27)
				)
				(hide yes)
			)
		)
		(property "Val" "20n/0.35A"
			(at 375.92 40.005 0)
			(effects
				(font
					(size 1.27 1.27)
					(thickness 0.15)
				)
				(justify right)
			)
		)
		(property "Manufacturer" "TDK"
			(at 391.16 31.75 0)
			(effects
				(font
					(size 1.27 1.27)
					(thickness 0.15)
				)
				(justify left bottom)
				(hide yes)
			)
		)
		(property "MPN" "MLG1005S20NJTD25"
			(at 393.7 31.75 0)
			(effects
				(font
					(size 1.27 1.27)
					(thickness 0.15)
				)
				(justify left bottom)
				(hide yes)
			)
		)
		(property "ISat" ""
			(at 394.97 31.75 0)
			(effects
				(font
					(size 1.27 1.27)
				)
				(justify left)
				(hide yes)
			)
		)
		(property "IMax" "0.35 A"
			(at 398.78 31.75 0)
			(effects
				(font
					(size 1.27 1.27)
					(thickness 0.15)
				)
				(justify left bottom)
				(hide yes)
			)
		)
		(property "Size" "1.0x0.5"
			(at 401.32 31.75 0)
			(effects
				(font
					(size 1.27 1.27)
					(thickness 0.15)
				)
				(justify left bottom)
				(hide yes)
			)
		)
		(property "Author" "Antmicro"
			(at 403.86 31.75 0)
			(effects
				(font
					(size 1.27 1.27)
					(thickness 0.15)
				)
				(justify left bottom)
				(hide yes)
			)
		)
		(property "License" "Apache-2.0"
			(at 406.4 31.75 0)
			(effects
				(font
					(size 1.27 1.27)
					(thickness 0.15)
				)
				(justify left bottom)
				(hide yes)
			)
		)
		(pin "2"
		)
		(pin "1"
		)
		(instances
			(project "data-center-rdimm-ddr5-tester"
				(path ""
					(reference "L4")
					(unit 1)
				)
			)
		)
	)
	(symbol
		(lib_id "antmicropower:GND")
		(at 334.01 110.49 0)
		(mirror y)
		(unit 1)
		(exclude_from_sim no)
		(in_bom yes)
		(on_board yes)
		(dnp no)
		(fields_autoplaced yes)
		(property "Reference" "#PWR0469"
			(at 334.01 116.84 0)
			(effects
				(font
					(size 1.27 1.27)
				)
				(hide yes)
			)
		)
		(property "Value" "GND"
			(at 335.915 114.935 0)
			(effects
				(font
					(size 1.27 1.27)
					(thickness 0.15)
				)
				(justify left bottom)
			)
		)
		(property "Footprint" ""
			(at 325.12 118.11 0)
			(effects
				(font
					(size 1.27 1.27)
					(thickness 0.15)
				)
				(justify left bottom)
				(hide yes)
			)
		)
		(property "Datasheet" ""
			(at 325.12 123.19 0)
			(effects
				(font
					(size 1.27 1.27)
					(thickness 0.15)
				)
				(justify left bottom)
				(hide yes)
			)
		)
		(property "Description" ""
			(at 334.01 110.49 0)
			(effects
				(font
					(size 1.27 1.27)
				)
				(hide yes)
			)
		)
		(property "Author" "Antmicro"
			(at 325.12 115.57 0)
			(effects
				(font
					(size 1.27 1.27)
					(thickness 0.15)
				)
				(justify left bottom)
				(hide yes)
			)
		)
		(property "License" "Apache-2.0"
			(at 325.12 118.11 0)
			(effects
				(font
					(size 1.27 1.27)
					(thickness 0.15)
				)
				(justify left bottom)
				(hide yes)
			)
		)
		(pin "1"
		)
		(instances
			(project "data-center-rdimm-ddr5-tester"
				(path ""
					(reference "#PWR0469")
					(unit 1)
				)
			)
		)
	)
)
